(kicad_sch
	(version 20231120)
	(generator "eeschema")
	(generator_version "8.0")
	(paper "A3")
	(title_block
		(title "Jetson Orin Baseboard")
		(date "2025-03-12")
		(rev "1.3.4")
		(company "Antmicro Ltd")
		(comment 1 "www.antmicro.com")
	)
	(junction
		(at 372.11 196.85)
		(diameter 0)
		(color 0 0 0 0)
	)
	(junction
		(at 361.95 106.68)
		(diameter 0)
		(color 0 0 0 0)
	)
	(junction
		(at 60.96 104.14)
		(diameter 0)
		(color 0 0 0 0)
	)
	(junction
		(at 35.56 91.44)
		(diameter 0)
		(color 0 0 0 0)
	)
	(junction
		(at 138.43 39.37)
		(diameter 0)
		(color 0 0 0 0)
	)
	(junction
		(at 344.17 149.86)
		(diameter 0)
		(color 0 0 0 0)
	)
	(junction
		(at 66.04 215.9)
		(diameter 0)
		(color 0 0 0 0)
	)
	(junction
		(at 185.42 201.93)
		(diameter 0)
		(color 0 0 0 0)
	)
	(junction
		(at 66.04 248.92)
		(diameter 0)
		(color 0 0 0 0)
	)
	(junction
		(at 284.48 60.96)
		(diameter 0)
		(color 0 0 0 0)
	)
	(junction
		(at 372.11 227.33)
		(diameter 0)
		(color 0 0 0 0)
	)
	(junction
		(at 361.95 60.96)
		(diameter 0)
		(color 0 0 0 0)
	)
	(junction
		(at 144.78 99.06)
		(diameter 0)
		(color 0 0 0 0)
	)
	(junction
		(at 72.39 139.7)
		(diameter 0)
		(color 0 0 0 0)
	)
	(junction
		(at 41.91 139.7)
		(diameter 0)
		(color 0 0 0 0)
	)
	(junction
		(at 328.93 154.94)
		(diameter 0)
		(color 0 0 0 0)
	)
	(junction
		(at 349.25 154.94)
		(diameter 0)
		(color 0 0 0 0)
	)
	(junction
		(at 341.63 238.76)
		(diameter 0)
		(color 0 0 0 0)
	)
	(junction
		(at 175.26 248.92)
		(diameter 0)
		(color 0 0 0 0)
	)
	(junction
		(at 361.95 160.02)
		(diameter 0)
		(color 0 0 0 0)
	)
	(junction
		(at 334.01 196.85)
		(diameter 0)
		(color 0 0 0 0)
	)
	(junction
		(at 147.32 46.99)
		(diameter 0)
		(color 0 0 0 0)
	)
	(junction
		(at 44.45 139.7)
		(diameter 0)
		(color 0 0 0 0)
	)
	(junction
		(at 284.48 68.58)
		(diameter 0)
		(color 0 0 0 0)
	)
	(junction
		(at 76.2 233.68)
		(diameter 0)
		(color 0 0 0 0)
	)
	(junction
		(at 35.56 139.7)
		(diameter 0)
		(color 0 0 0 0)
	)
	(junction
		(at 334.01 227.33)
		(diameter 0)
		(color 0 0 0 0)
	)
	(junction
		(at 284.48 106.68)
		(diameter 0)
		(color 0 0 0 0)
	)
	(junction
		(at 359.41 149.86)
		(diameter 0)
		(color 0 0 0 0)
	)
	(junction
		(at 147.32 101.6)
		(diameter 0)
		(color 0 0 0 0)
	)
	(junction
		(at 144.78 44.45)
		(diameter 0)
		(color 0 0 0 0)
	)
	(junction
		(at 251.46 154.94)
		(diameter 0)
		(color 0 0 0 0)
	)
	(junction
		(at 341.63 209.55)
		(diameter 0)
		(color 0 0 0 0)
	)
	(junction
		(at 284.48 99.06)
		(diameter 0)
		(color 0 0 0 0)
	)
	(junction
		(at 175.26 215.9)
		(diameter 0)
		(color 0 0 0 0)
	)
	(junction
		(at 361.95 99.06)
		(diameter 0)
		(color 0 0 0 0)
	)
	(junction
		(at 361.95 68.58)
		(diameter 0)
		(color 0 0 0 0)
	)
	(junction
		(at 76.2 201.93)
		(diameter 0)
		(color 0 0 0 0)
	)
	(junction
		(at 281.94 154.94)
		(diameter 0)
		(color 0 0 0 0)
	)
	(junction
		(at 271.78 154.94)
		(diameter 0)
		(color 0 0 0 0)
	)
	(junction
		(at 284.48 160.02)
		(diameter 0)
		(color 0 0 0 0)
	)
	(junction
		(at 361.95 162.56)
		(diameter 0)
		(color 0 0 0 0)
	)
	(junction
		(at 140.97 41.91)
		(diameter 0)
		(color 0 0 0 0)
	)
	(junction
		(at 60.96 96.52)
		(diameter 0)
		(color 0 0 0 0)
	)
	(junction
		(at 359.41 154.94)
		(diameter 0)
		(color 0 0 0 0)
	)
	(junction
		(at 140.97 96.52)
		(diameter 0)
		(color 0 0 0 0)
	)
	(junction
		(at 323.85 149.86)
		(diameter 0)
		(color 0 0 0 0)
	)
	(junction
		(at 49.53 44.45)
		(diameter 0)
		(color 0 0 0 0)
	)
	(junction
		(at 185.42 233.68)
		(diameter 0)
		(color 0 0 0 0)
	)
	(junction
		(at 246.38 149.86)
		(diameter 0)
		(color 0 0 0 0)
	)
	(junction
		(at 86.36 231.14)
		(diameter 0)
		(color 0 0 0 0)
	)
	(junction
		(at 266.7 149.86)
		(diameter 0)
		(color 0 0 0 0)
	)
	(junction
		(at 284.48 162.56)
		(diameter 0)
		(color 0 0 0 0)
	)
	(junction
		(at 138.43 93.98)
		(diameter 0)
		(color 0 0 0 0)
	)
	(junction
		(at 195.58 231.14)
		(diameter 0)
		(color 0 0 0 0)
	)
	(junction
		(at 78.74 139.7)
		(diameter 0)
		(color 0 0 0 0)
	)
	(junction
		(at 83.82 139.7)
		(diameter 0)
		(color 0 0 0 0)
	)
	(junction
		(at 195.58 213.36)
		(diameter 0)
		(color 0 0 0 0)
	)
	(junction
		(at 281.94 149.86)
		(diameter 0)
		(color 0 0 0 0)
	)
	(junction
		(at 86.36 213.36)
		(diameter 0)
		(color 0 0 0 0)
	)
	(junction
		(at 361.95 76.2)
		(diameter 0)
		(color 0 0 0 0)
	)
	(junction
		(at 284.48 76.2)
		(diameter 0)
		(color 0 0 0 0)
	)
	(junction
		(at 46.99 139.7)
		(diameter 0)
		(color 0 0 0 0)
	)
	(junction
		(at 81.28 139.7)
		(diameter 0)
		(color 0 0 0 0)
	)
	(no_connect
		(at 364.49 40.64)
	)
	(no_connect
		(at 364.49 33.02)
	)
	(no_connect
		(at 364.49 35.56)
	)
	(no_connect
		(at 364.49 38.1)
	)
	(no_connect
		(at 287.02 142.24)
	)
	(no_connect
		(at 287.02 147.32)
	)
	(no_connect
		(at 364.49 83.82)
	)
	(no_connect
		(at 364.49 124.46)
	)
	(no_connect
		(at 364.49 86.36)
	)
	(no_connect
		(at 364.49 147.32)
	)
	(no_connect
		(at 62.23 101.6)
	)
	(no_connect
		(at 364.49 119.38)
	)
	(no_connect
		(at 364.49 78.74)
	)
	(no_connect
		(at 364.49 127)
	)
	(no_connect
		(at 287.02 139.7)
	)
	(no_connect
		(at 364.49 144.78)
	)
	(no_connect
		(at 364.49 81.28)
	)
	(no_connect
		(at 364.49 139.7)
	)
	(no_connect
		(at 364.49 121.92)
	)
	(no_connect
		(at 287.02 63.5)
	)
	(no_connect
		(at 287.02 66.04)
	)
	(no_connect
		(at 287.02 71.12)
	)
	(no_connect
		(at 287.02 73.66)
	)
	(no_connect
		(at 287.02 114.3)
	)
	(no_connect
		(at 287.02 109.22)
	)
	(no_connect
		(at 287.02 119.38)
	)
	(no_connect
		(at 287.02 121.92)
	)
	(no_connect
		(at 287.02 124.46)
	)
	(no_connect
		(at 287.02 127)
	)
	(no_connect
		(at 364.49 63.5)
	)
	(no_connect
		(at 364.49 66.04)
	)
	(no_connect
		(at 364.49 71.12)
	)
	(no_connect
		(at 364.49 73.66)
	)
	(no_connect
		(at 364.49 109.22)
	)
	(no_connect
		(at 364.49 114.3)
	)
	(no_connect
		(at 364.49 142.24)
	)
	(no_connect
		(at 287.02 144.78)
	)
	(wire
		(pts
			(xy 144.78 62.23) (xy 157.48 62.23)
		)
		(stroke
			(width 0)
			(type default)
		)
	)
	(wire
		(pts
			(xy 195.58 213.36) (xy 201.93 213.36)
		)
		(stroke
			(width 0)
			(type default)
		)
	)
	(wire
		(pts
			(xy 232.41 252.73) (xy 232.41 254)
		)
		(stroke
			(width 0)
			(type default)
		)
	)
	(wire
		(pts
			(xy 344.17 91.44) (xy 364.49 91.44)
		)
		(stroke
			(width 0)
			(type default)
		)
	)
	(wire
		(pts
			(xy 364.49 196.85) (xy 372.11 196.85)
		)
		(stroke
			(width 0)
			(type default)
		)
	)
	(wire
		(pts
			(xy 138.43 121.92) (xy 157.48 121.92)
		)
		(stroke
			(width 0)
			(type default)
		)
	)
	(wire
		(pts
			(xy 341.63 227.33) (xy 334.01 227.33)
		)
		(stroke
			(width 0)
			(type default)
		)
	)
	(wire
		(pts
			(xy 138.43 67.31) (xy 157.48 67.31)
		)
		(stroke
			(width 0)
			(type default)
		)
	)
	(wire
		(pts
			(xy 76.2 240.03) (xy 76.2 241.3)
		)
		(stroke
			(width 0)
			(type default)
		)
	)
	(wire
		(pts
			(xy 134.62 41.91) (xy 140.97 41.91)
		)
		(stroke
			(width 0)
			(type default)
		)
	)
	(wire
		(pts
			(xy 361.95 76.2) (xy 361.95 99.06)
		)
		(stroke
			(width 0)
			(type default)
		)
	)
	(wire
		(pts
			(xy 281.94 48.26) (xy 287.02 48.26)
		)
		(stroke
			(width 0)
			(type default)
		)
	)
	(wire
		(pts
			(xy 64.77 129.54) (xy 64.77 130.81)
		)
		(stroke
			(width 0)
			(type default)
		)
	)
	(wire
		(pts
			(xy 66.04 215.9) (xy 92.71 215.9)
		)
		(stroke
			(width 0)
			(type default)
		)
	)
	(wire
		(pts
			(xy 66.04 248.92) (xy 92.71 248.92)
		)
		(stroke
			(width 0)
			(type default)
		)
	)
	(wire
		(pts
			(xy 266.7 40.64) (xy 287.02 40.64)
		)
		(stroke
			(width 0)
			(type default)
		)
	)
	(wire
		(pts
			(xy 361.95 76.2) (xy 364.49 76.2)
		)
		(stroke
			(width 0)
			(type default)
		)
	)
	(wire
		(pts
			(xy 107.95 213.36) (xy 123.19 213.36)
		)
		(stroke
			(width 0)
			(type default)
		)
	)
	(wire
		(pts
			(xy 328.93 167.64) (xy 328.93 168.91)
		)
		(stroke
			(width 0)
			(type default)
		)
	)
	(wire
		(pts
			(xy 195.58 200.66) (xy 195.58 203.2)
		)
		(stroke
			(width 0)
			(type default)
		)
	)
	(wire
		(pts
			(xy 31.75 60.96) (xy 35.56 60.96)
		)
		(stroke
			(width 0)
			(type default)
		)
	)
	(wire
		(pts
			(xy 78.74 139.7) (xy 81.28 139.7)
		)
		(stroke
			(width 0)
			(type default)
		)
	)
	(wire
		(pts
			(xy 344.17 50.8) (xy 364.49 50.8)
		)
		(stroke
			(width 0)
			(type default)
		)
	)
	(wire
		(pts
			(xy 167.64 62.23) (xy 186.69 62.23)
		)
		(stroke
			(width 0)
			(type default)
		)
	)
	(wire
		(pts
			(xy 82.55 101.6) (xy 97.79 101.6)
		)
		(stroke
			(width 0)
			(type default)
		)
	)
	(wire
		(pts
			(xy 175.26 208.28) (xy 175.26 215.9)
		)
		(stroke
			(width 0)
			(type default)
		)
	)
	(polyline
		(pts
			(xy 340.36 87.63) (xy 340.36 105.41)
		)
		(stroke
			(width 0)
			(type solid)
		)
	)
	(wire
		(pts
			(xy 251.46 167.64) (xy 251.46 168.91)
		)
		(stroke
			(width 0)
			(type default)
		)
	)
	(wire
		(pts
			(xy 82.55 66.04) (xy 92.71 66.04)
		)
		(stroke
			(width 0)
			(type default)
		)
	)
	(wire
		(pts
			(xy 266.7 33.02) (xy 287.02 33.02)
		)
		(stroke
			(width 0)
			(type default)
		)
	)
	(wire
		(pts
			(xy 134.62 96.52) (xy 140.97 96.52)
		)
		(stroke
			(width 0)
			(type default)
		)
	)
	(wire
		(pts
			(xy 256.54 134.62) (xy 273.05 134.62)
		)
		(stroke
			(width 0)
			(type default)
		)
	)
	(wire
		(pts
			(xy 344.17 96.52) (xy 364.49 96.52)
		)
		(stroke
			(width 0)
			(type default)
		)
	)
	(wire
		(pts
			(xy 266.7 81.28) (xy 287.02 81.28)
		)
		(stroke
			(width 0)
			(type default)
		)
	)
	(wire
		(pts
			(xy 60.96 104.14) (xy 62.23 104.14)
		)
		(stroke
			(width 0)
			(type default)
		)
	)
	(wire
		(pts
			(xy 60.96 215.9) (xy 66.04 215.9)
		)
		(stroke
			(width 0)
			(type default)
		)
	)
	(wire
		(pts
			(xy 134.62 39.37) (xy 138.43 39.37)
		)
		(stroke
			(width 0)
			(type default)
		)
	)
	(wire
		(pts
			(xy 361.95 162.56) (xy 364.49 162.56)
		)
		(stroke
			(width 0)
			(type default)
		)
	)
	(wire
		(pts
			(xy 167.64 121.92) (xy 186.69 121.92)
		)
		(stroke
			(width 0)
			(type default)
		)
	)
	(wire
		(pts
			(xy 86.36 200.66) (xy 86.36 203.2)
		)
		(stroke
			(width 0)
			(type default)
		)
	)
	(polyline
		(pts
			(xy 299.72 252.73) (xy 299.72 199.39)
		)
		(stroke
			(width 0)
			(type default)
		)
	)
	(wire
		(pts
			(xy 281.94 58.42) (xy 287.02 58.42)
		)
		(stroke
			(width 0)
			(type default)
		)
	)
	(wire
		(pts
			(xy 284.48 76.2) (xy 284.48 99.06)
		)
		(stroke
			(width 0)
			(type default)
		)
	)
	(wire
		(pts
			(xy 107.95 248.92) (xy 109.22 248.92)
		)
		(stroke
			(width 0)
			(type default)
		)
	)
	(wire
		(pts
			(xy 41.91 151.13) (xy 41.91 153.67)
		)
		(stroke
			(width 0)
			(type default)
		)
	)
	(wire
		(pts
			(xy 167.64 46.99) (xy 186.69 46.99)
		)
		(stroke
			(width 0)
			(type default)
		)
	)
	(wire
		(pts
			(xy 251.46 161.29) (xy 251.46 162.56)
		)
		(stroke
			(width 0)
			(type default)
		)
	)
	(wire
		(pts
			(xy 256.54 129.54) (xy 273.05 129.54)
		)
		(stroke
			(width 0)
			(type default)
		)
	)
	(wire
		(pts
			(xy 271.78 154.94) (xy 271.78 156.21)
		)
		(stroke
			(width 0)
			(type default)
		)
	)
	(wire
		(pts
			(xy 67.31 162.56) (xy 86.36 162.56)
		)
		(stroke
			(width 0)
			(type default)
		)
	)
	(wire
		(pts
			(xy 60.96 105.41) (xy 60.96 104.14)
		)
		(stroke
			(width 0)
			(type default)
		)
	)
	(wire
		(pts
			(xy 195.58 231.14) (xy 195.58 246.38)
		)
		(stroke
			(width 0)
			(type default)
		)
	)
	(wire
		(pts
			(xy 144.78 116.84) (xy 157.48 116.84)
		)
		(stroke
			(width 0)
			(type default)
		)
	)
	(wire
		(pts
			(xy 284.48 106.68) (xy 284.48 160.02)
		)
		(stroke
			(width 0)
			(type default)
		)
	)
	(wire
		(pts
			(xy 82.55 58.42) (xy 92.71 58.42)
		)
		(stroke
			(width 0)
			(type default)
		)
	)
	(wire
		(pts
			(xy 46.99 151.13) (xy 46.99 160.02)
		)
		(stroke
			(width 0)
			(type default)
		)
	)
	(wire
		(pts
			(xy 76.2 232.41) (xy 76.2 233.68)
		)
		(stroke
			(width 0)
			(type default)
		)
	)
	(wire
		(pts
			(xy 72.39 135.89) (xy 72.39 139.7)
		)
		(stroke
			(width 0)
			(type default)
		)
	)
	(wire
		(pts
			(xy 364.49 246.38) (xy 364.49 247.65)
		)
		(stroke
			(width 0)
			(type default)
		)
	)
	(wire
		(pts
			(xy 60.96 96.52) (xy 62.23 96.52)
		)
		(stroke
			(width 0)
			(type default)
		)
	)
	(wire
		(pts
			(xy 363.22 209.55) (xy 364.49 209.55)
		)
		(stroke
			(width 0)
			(type default)
		)
	)
	(wire
		(pts
			(xy 323.85 149.86) (xy 323.85 156.21)
		)
		(stroke
			(width 0)
			(type default)
		)
	)
	(wire
		(pts
			(xy 266.7 86.36) (xy 287.02 86.36)
		)
		(stroke
			(width 0)
			(type default)
		)
	)
	(wire
		(pts
			(xy 138.43 39.37) (xy 157.48 39.37)
		)
		(stroke
			(width 0)
			(type default)
		)
	)
	(polyline
		(pts
			(xy 190.5 50.8) (xy 190.5 69.85)
		)
		(stroke
			(width 0)
			(type solid)
		)
	)
	(wire
		(pts
			(xy 193.04 210.82) (xy 201.93 210.82)
		)
		(stroke
			(width 0)
			(type default)
		)
	)
	(wire
		(pts
			(xy 224.79 149.86) (xy 246.38 149.86)
		)
		(stroke
			(width 0)
			(type default)
		)
	)
	(wire
		(pts
			(xy 359.41 154.94) (xy 359.41 157.48)
		)
		(stroke
			(width 0)
			(type default)
		)
	)
	(wire
		(pts
			(xy 281.94 45.72) (xy 287.02 45.72)
		)
		(stroke
			(width 0)
			(type default)
		)
	)
	(wire
		(pts
			(xy 170.18 215.9) (xy 175.26 215.9)
		)
		(stroke
			(width 0)
			(type default)
		)
	)
	(polyline
		(pts
			(xy 190.5 83.82) (xy 190.5 102.87)
		)
		(stroke
			(width 0)
			(type solid)
		)
	)
	(wire
		(pts
			(xy 185.42 240.03) (xy 185.42 241.3)
		)
		(stroke
			(width 0)
			(type default)
		)
	)
	(wire
		(pts
			(xy 144.78 44.45) (xy 144.78 62.23)
		)
		(stroke
			(width 0)
			(type default)
		)
	)
	(wire
		(pts
			(xy 167.64 116.84) (xy 186.69 116.84)
		)
		(stroke
			(width 0)
			(type default)
		)
	)
	(wire
		(pts
			(xy 138.43 93.98) (xy 138.43 121.92)
		)
		(stroke
			(width 0)
			(type default)
		)
	)
	(wire
		(pts
			(xy 341.63 217.17) (xy 342.9 217.17)
		)
		(stroke
			(width 0)
			(type default)
		)
	)
	(wire
		(pts
			(xy 109.22 215.9) (xy 109.22 220.98)
		)
		(stroke
			(width 0)
			(type default)
		)
	)
	(wire
		(pts
			(xy 360.68 58.42) (xy 364.49 58.42)
		)
		(stroke
			(width 0)
			(type default)
		)
	)
	(wire
		(pts
			(xy 49.53 43.18) (xy 49.53 44.45)
		)
		(stroke
			(width 0)
			(type default)
		)
	)
	(wire
		(pts
			(xy 359.41 152.4) (xy 359.41 149.86)
		)
		(stroke
			(width 0)
			(type default)
		)
	)
	(wire
		(pts
			(xy 26.67 139.7) (xy 35.56 139.7)
		)
		(stroke
			(width 0)
			(type default)
		)
	)
	(wire
		(pts
			(xy 60.96 93.98) (xy 62.23 93.98)
		)
		(stroke
			(width 0)
			(type default)
		)
	)
	(wire
		(pts
			(xy 217.17 213.36) (xy 232.41 213.36)
		)
		(stroke
			(width 0)
			(type default)
		)
	)
	(wire
		(pts
			(xy 167.64 59.69) (xy 186.69 59.69)
		)
		(stroke
			(width 0)
			(type default)
		)
	)
	(wire
		(pts
			(xy 284.48 163.83) (xy 284.48 162.56)
		)
		(stroke
			(width 0)
			(type default)
		)
	)
	(wire
		(pts
			(xy 134.62 101.6) (xy 147.32 101.6)
		)
		(stroke
			(width 0)
			(type default)
		)
	)
	(wire
		(pts
			(xy 284.48 76.2) (xy 287.02 76.2)
		)
		(stroke
			(width 0)
			(type default)
		)
	)
	(wire
		(pts
			(xy 372.11 233.68) (xy 372.11 234.95)
		)
		(stroke
			(width 0)
			(type default)
		)
	)
	(wire
		(pts
			(xy 284.48 162.56) (xy 287.02 162.56)
		)
		(stroke
			(width 0)
			(type default)
		)
	)
	(wire
		(pts
			(xy 281.94 157.48) (xy 287.02 157.48)
		)
		(stroke
			(width 0)
			(type default)
		)
	)
	(wire
		(pts
			(xy 360.68 101.6) (xy 364.49 101.6)
		)
		(stroke
			(width 0)
			(type default)
		)
	)
	(wire
		(pts
			(xy 26.67 135.89) (xy 26.67 139.7)
		)
		(stroke
			(width 0)
			(type default)
		)
	)
	(wire
		(pts
			(xy 144.78 44.45) (xy 157.48 44.45)
		)
		(stroke
			(width 0)
			(type default)
		)
	)
	(wire
		(pts
			(xy 302.26 154.94) (xy 328.93 154.94)
		)
		(stroke
			(width 0)
			(type default)
		)
	)
	(wire
		(pts
			(xy 256.54 137.16) (xy 273.05 137.16)
		)
		(stroke
			(width 0)
			(type default)
		)
	)
	(wire
		(pts
			(xy 328.93 156.21) (xy 328.93 154.94)
		)
		(stroke
			(width 0)
			(type default)
		)
	)
	(wire
		(pts
			(xy 59.69 48.26) (xy 59.69 44.45)
		)
		(stroke
			(width 0)
			(type default)
		)
	)
	(wire
		(pts
			(xy 82.55 81.28) (xy 97.79 81.28)
		)
		(stroke
			(width 0)
			(type default)
		)
	)
	(wire
		(pts
			(xy 86.36 213.36) (xy 86.36 231.14)
		)
		(stroke
			(width 0)
			(type default)
		)
	)
	(wire
		(pts
			(xy 342.9 209.55) (xy 341.63 209.55)
		)
		(stroke
			(width 0)
			(type default)
		)
	)
	(wire
		(pts
			(xy 364.49 217.17) (xy 364.49 218.44)
		)
		(stroke
			(width 0)
			(type default)
		)
	)
	(wire
		(pts
			(xy 364.49 227.33) (xy 372.11 227.33)
		)
		(stroke
			(width 0)
			(type default)
		)
	)
	(wire
		(pts
			(xy 82.55 104.14) (xy 97.79 104.14)
		)
		(stroke
			(width 0)
			(type default)
		)
	)
	(wire
		(pts
			(xy 340.36 243.84) (xy 342.9 243.84)
		)
		(stroke
			(width 0)
			(type default)
		)
	)
	(wire
		(pts
			(xy 86.36 139.7) (xy 86.36 140.97)
		)
		(stroke
			(width 0)
			(type default)
		)
	)
	(wire
		(pts
			(xy 323.85 149.86) (xy 344.17 149.86)
		)
		(stroke
			(width 0)
			(type default)
		)
	)
	(wire
		(pts
			(xy 281.94 91.44) (xy 287.02 91.44)
		)
		(stroke
			(width 0)
			(type default)
		)
	)
	(wire
		(pts
			(xy 360.68 129.54) (xy 364.49 129.54)
		)
		(stroke
			(width 0)
			(type default)
		)
	)
	(wire
		(pts
			(xy 361.95 60.96) (xy 361.95 68.58)
		)
		(stroke
			(width 0)
			(type default)
		)
	)
	(wire
		(pts
			(xy 60.96 96.52) (xy 60.96 104.14)
		)
		(stroke
			(width 0)
			(type default)
		)
	)
	(polyline
		(pts
			(xy 299.72 199.39) (xy 299.72 180.34)
		)
		(stroke
			(width 0)
			(type default)
		)
	)
	(wire
		(pts
			(xy 344.17 93.98) (xy 364.49 93.98)
		)
		(stroke
			(width 0)
			(type default)
		)
	)
	(wire
		(pts
			(xy 217.17 246.38) (xy 232.41 246.38)
		)
		(stroke
			(width 0)
			(type default)
		)
	)
	(wire
		(pts
			(xy 167.64 67.31) (xy 186.69 67.31)
		)
		(stroke
			(width 0)
			(type default)
		)
	)
	(wire
		(pts
			(xy 271.78 161.29) (xy 271.78 162.56)
		)
		(stroke
			(width 0)
			(type default)
		)
	)
	(wire
		(pts
			(xy 284.48 160.02) (xy 284.48 162.56)
		)
		(stroke
			(width 0)
			(type default)
		)
	)
	(wire
		(pts
			(xy 334.01 137.16) (xy 350.52 137.16)
		)
		(stroke
			(width 0)
			(type default)
		)
	)
	(wire
		(pts
			(xy 109.22 248.92) (xy 109.22 254)
		)
		(stroke
			(width 0)
			(type default)
		)
	)
	(wire
		(pts
			(xy 35.56 91.44) (xy 62.23 91.44)
		)
		(stroke
			(width 0)
			(type default)
		)
	)
	(wire
		(pts
			(xy 193.04 201.93) (xy 193.04 210.82)
		)
		(stroke
			(width 0)
			(type default)
		)
	)
	(wire
		(pts
			(xy 175.26 248.92) (xy 201.93 248.92)
		)
		(stroke
			(width 0)
			(type default)
		)
	)
	(wire
		(pts
			(xy 72.39 139.7) (xy 78.74 139.7)
		)
		(stroke
			(width 0)
			(type default)
		)
	)
	(wire
		(pts
			(xy 82.55 78.74) (xy 97.79 78.74)
		)
		(stroke
			(width 0)
			(type default)
		)
	)
	(polyline
		(pts
			(xy 180.34 139.7) (xy 180.34 162.56)
		)
		(stroke
			(width 0)
			(type solid)
		)
	)
	(wire
		(pts
			(xy 66.04 248.92) (xy 66.04 250.19)
		)
		(stroke
			(width 0)
			(type default)
		)
	)
	(wire
		(pts
			(xy 363.22 243.84) (xy 381 243.84)
		)
		(stroke
			(width 0)
			(type default)
		)
	)
	(wire
		(pts
			(xy 360.68 55.88) (xy 364.49 55.88)
		)
		(stroke
			(width 0)
			(type default)
		)
	)
	(wire
		(pts
			(xy 334.01 129.54) (xy 350.52 129.54)
		)
		(stroke
			(width 0)
			(type default)
		)
	)
	(wire
		(pts
			(xy 59.69 44.45) (xy 49.53 44.45)
		)
		(stroke
			(width 0)
			(type default)
		)
	)
	(wire
		(pts
			(xy 284.48 99.06) (xy 287.02 99.06)
		)
		(stroke
			(width 0)
			(type default)
		)
	)
	(wire
		(pts
			(xy 251.46 156.21) (xy 251.46 154.94)
		)
		(stroke
			(width 0)
			(type default)
		)
	)
	(wire
		(pts
			(xy 86.36 231.14) (xy 86.36 246.38)
		)
		(stroke
			(width 0)
			(type default)
		)
	)
	(wire
		(pts
			(xy 49.53 151.13) (xy 49.53 162.56)
		)
		(stroke
			(width 0)
			(type default)
		)
	)
	(polyline
		(pts
			(xy 257.81 31.75) (xy 257.81 59.69)
		)
		(stroke
			(width 0)
			(type solid)
		)
	)
	(wire
		(pts
			(xy 266.7 149.86) (xy 281.94 149.86)
		)
		(stroke
			(width 0)
			(type default)
		)
	)
	(wire
		(pts
			(xy 284.48 106.68) (xy 287.02 106.68)
		)
		(stroke
			(width 0)
			(type default)
		)
	)
	(wire
		(pts
			(xy 82.55 88.9) (xy 97.79 88.9)
		)
		(stroke
			(width 0)
			(type default)
		)
	)
	(wire
		(pts
			(xy 147.32 46.99) (xy 157.48 46.99)
		)
		(stroke
			(width 0)
			(type default)
		)
	)
	(wire
		(pts
			(xy 232.41 246.38) (xy 232.41 247.65)
		)
		(stroke
			(width 0)
			(type default)
		)
	)
	(wire
		(pts
			(xy 359.41 157.48) (xy 364.49 157.48)
		)
		(stroke
			(width 0)
			(type default)
		)
	)
	(wire
		(pts
			(xy 60.96 96.52) (xy 60.96 93.98)
		)
		(stroke
			(width 0)
			(type default)
		)
	)
	(wire
		(pts
			(xy 81.28 151.13) (xy 81.28 156.21)
		)
		(stroke
			(width 0)
			(type default)
		)
	)
	(polyline
		(pts
			(xy 257.81 77.47) (xy 257.81 105.41)
		)
		(stroke
			(width 0)
			(type solid)
		)
	)
	(wire
		(pts
			(xy 232.41 219.71) (xy 232.41 220.98)
		)
		(stroke
			(width 0)
			(type default)
		)
	)
	(wire
		(pts
			(xy 66.04 208.28) (xy 66.04 215.9)
		)
		(stroke
			(width 0)
			(type default)
		)
	)
	(wire
		(pts
			(xy 123.19 219.71) (xy 123.19 220.98)
		)
		(stroke
			(width 0)
			(type default)
		)
	)
	(wire
		(pts
			(xy 76.2 233.68) (xy 76.2 234.95)
		)
		(stroke
			(width 0)
			(type default)
		)
	)
	(wire
		(pts
			(xy 195.58 231.14) (xy 198.12 231.14)
		)
		(stroke
			(width 0)
			(type default)
		)
	)
	(wire
		(pts
			(xy 340.36 214.63) (xy 342.9 214.63)
		)
		(stroke
			(width 0)
			(type default)
		)
	)
	(wire
		(pts
			(xy 86.36 213.36) (xy 92.71 213.36)
		)
		(stroke
			(width 0)
			(type default)
		)
	)
	(wire
		(pts
			(xy 363.22 246.38) (xy 364.49 246.38)
		)
		(stroke
			(width 0)
			(type default)
		)
	)
	(wire
		(pts
			(xy 185.42 208.28) (xy 185.42 209.55)
		)
		(stroke
			(width 0)
			(type default)
		)
	)
	(polyline
		(pts
			(xy 129.54 139.7) (xy 180.34 139.7)
		)
		(stroke
			(width 0)
			(type solid)
		)
	)
	(wire
		(pts
			(xy 340.36 212.09) (xy 342.9 212.09)
		)
		(stroke
			(width 0)
			(type default)
		)
	)
	(wire
		(pts
			(xy 363.22 217.17) (xy 364.49 217.17)
		)
		(stroke
			(width 0)
			(type default)
		)
	)
	(wire
		(pts
			(xy 284.48 68.58) (xy 284.48 76.2)
		)
		(stroke
			(width 0)
			(type default)
		)
	)
	(wire
		(pts
			(xy 175.26 248.92) (xy 175.26 250.19)
		)
		(stroke
			(width 0)
			(type default)
		)
	)
	(wire
		(pts
			(xy 41.91 139.7) (xy 44.45 139.7)
		)
		(stroke
			(width 0)
			(type default)
		)
	)
	(polyline
		(pts
			(xy 190.5 105.41) (xy 190.5 124.46)
		)
		(stroke
			(width 0)
			(type solid)
		)
	)
	(wire
		(pts
			(xy 81.28 139.7) (xy 83.82 139.7)
		)
		(stroke
			(width 0)
			(type default)
		)
	)
	(wire
		(pts
			(xy 195.58 213.36) (xy 195.58 231.14)
		)
		(stroke
			(width 0)
			(type default)
		)
	)
	(wire
		(pts
			(xy 78.74 151.13) (xy 78.74 153.67)
		)
		(stroke
			(width 0)
			(type default)
		)
	)
	(wire
		(pts
			(xy 78.74 140.97) (xy 78.74 139.7)
		)
		(stroke
			(width 0)
			(type default)
		)
	)
	(wire
		(pts
			(xy 224.79 154.94) (xy 251.46 154.94)
		)
		(stroke
			(width 0)
			(type default)
		)
	)
	(wire
		(pts
			(xy 147.32 114.3) (xy 157.48 114.3)
		)
		(stroke
			(width 0)
			(type default)
		)
	)
	(wire
		(pts
			(xy 185.42 232.41) (xy 185.42 233.68)
		)
		(stroke
			(width 0)
			(type default)
		)
	)
	(wire
		(pts
			(xy 334.01 233.68) (xy 334.01 234.95)
		)
		(stroke
			(width 0)
			(type default)
		)
	)
	(wire
		(pts
			(xy 134.62 99.06) (xy 144.78 99.06)
		)
		(stroke
			(width 0)
			(type default)
		)
	)
	(wire
		(pts
			(xy 66.04 255.27) (xy 66.04 256.54)
		)
		(stroke
			(width 0)
			(type default)
		)
	)
	(wire
		(pts
			(xy 334.01 227.33) (xy 334.01 228.6)
		)
		(stroke
			(width 0)
			(type default)
		)
	)
	(wire
		(pts
			(xy 107.95 243.84) (xy 123.19 243.84)
		)
		(stroke
			(width 0)
			(type default)
		)
	)
	(wire
		(pts
			(xy 76.2 201.93) (xy 76.2 203.2)
		)
		(stroke
			(width 0)
			(type default)
		)
	)
	(wire
		(pts
			(xy 246.38 161.29) (xy 246.38 162.56)
		)
		(stroke
			(width 0)
			(type default)
		)
	)
	(wire
		(pts
			(xy 83.82 201.93) (xy 76.2 201.93)
		)
		(stroke
			(width 0)
			(type default)
		)
	)
	(wire
		(pts
			(xy 35.56 99.06) (xy 35.56 101.6)
		)
		(stroke
			(width 0)
			(type default)
		)
	)
	(wire
		(pts
			(xy 123.19 246.38) (xy 123.19 247.65)
		)
		(stroke
			(width 0)
			(type default)
		)
	)
	(wire
		(pts
			(xy 361.95 160.02) (xy 364.49 160.02)
		)
		(stroke
			(width 0)
			(type default)
		)
	)
	(wire
		(pts
			(xy 40.64 63.5) (xy 62.23 63.5)
		)
		(stroke
			(width 0)
			(type default)
		)
	)
	(wire
		(pts
			(xy 195.58 208.28) (xy 195.58 213.36)
		)
		(stroke
			(width 0)
			(type default)
		)
	)
	(wire
		(pts
			(xy 107.95 210.82) (xy 123.19 210.82)
		)
		(stroke
			(width 0)
			(type default)
		)
	)
	(wire
		(pts
			(xy 281.94 55.88) (xy 287.02 55.88)
		)
		(stroke
			(width 0)
			(type default)
		)
	)
	(wire
		(pts
			(xy 83.82 151.13) (xy 83.82 160.02)
		)
		(stroke
			(width 0)
			(type default)
		)
	)
	(wire
		(pts
			(xy 201.93 246.38) (xy 195.58 246.38)
		)
		(stroke
			(width 0)
			(type default)
		)
	)
	(polyline
		(pts
			(xy 261.62 87.63) (xy 261.62 105.41)
		)
		(stroke
			(width 0)
			(type solid)
		)
	)
	(wire
		(pts
			(xy 86.36 208.28) (xy 86.36 213.36)
		)
		(stroke
			(width 0)
			(type default)
		)
	)
	(wire
		(pts
			(xy 46.99 139.7) (xy 49.53 139.7)
		)
		(stroke
			(width 0)
			(type default)
		)
	)
	(wire
		(pts
			(xy 266.7 78.74) (xy 287.02 78.74)
		)
		(stroke
			(width 0)
			(type default)
		)
	)
	(wire
		(pts
			(xy 284.48 68.58) (xy 287.02 68.58)
		)
		(stroke
			(width 0)
			(type default)
		)
	)
	(wire
		(pts
			(xy 266.7 83.82) (xy 287.02 83.82)
		)
		(stroke
			(width 0)
			(type default)
		)
	)
	(wire
		(pts
			(xy 107.95 215.9) (xy 109.22 215.9)
		)
		(stroke
			(width 0)
			(type default)
		)
	)
	(wire
		(pts
			(xy 344.17 43.18) (xy 364.49 43.18)
		)
		(stroke
			(width 0)
			(type default)
		)
	)
	(wire
		(pts
			(xy 144.78 99.06) (xy 144.78 116.84)
		)
		(stroke
			(width 0)
			(type default)
		)
	)
	(wire
		(pts
			(xy 281.94 149.86) (xy 287.02 149.86)
		)
		(stroke
			(width 0)
			(type default)
		)
	)
	(wire
		(pts
			(xy 372.11 226.06) (xy 372.11 227.33)
		)
		(stroke
			(width 0)
			(type default)
		)
	)
	(wire
		(pts
			(xy 217.17 243.84) (xy 232.41 243.84)
		)
		(stroke
			(width 0)
			(type default)
		)
	)
	(wire
		(pts
			(xy 217.17 215.9) (xy 218.44 215.9)
		)
		(stroke
			(width 0)
			(type default)
		)
	)
	(wire
		(pts
			(xy 167.64 96.52) (xy 186.69 96.52)
		)
		(stroke
			(width 0)
			(type default)
		)
	)
	(wire
		(pts
			(xy 123.19 252.73) (xy 123.19 254)
		)
		(stroke
			(width 0)
			(type default)
		)
	)
	(wire
		(pts
			(xy 49.53 139.7) (xy 49.53 140.97)
		)
		(stroke
			(width 0)
			(type default)
		)
	)
	(wire
		(pts
			(xy 140.97 41.91) (xy 140.97 64.77)
		)
		(stroke
			(width 0)
			(type default)
		)
	)
	(wire
		(pts
			(xy 364.49 209.55) (xy 364.49 196.85)
		)
		(stroke
			(width 0)
			(type default)
		)
	)
	(wire
		(pts
			(xy 49.53 50.8) (xy 49.53 52.07)
		)
		(stroke
			(width 0)
			(type default)
		)
	)
	(wire
		(pts
			(xy 334.01 203.2) (xy 334.01 204.47)
		)
		(stroke
			(width 0)
			(type default)
		)
	)
	(wire
		(pts
			(xy 35.56 129.54) (xy 35.56 130.81)
		)
		(stroke
			(width 0)
			(type default)
		)
	)
	(wire
		(pts
			(xy 175.26 255.27) (xy 175.26 256.54)
		)
		(stroke
			(width 0)
			(type default)
		)
	)
	(wire
		(pts
			(xy 64.77 139.7) (xy 72.39 139.7)
		)
		(stroke
			(width 0)
			(type default)
		)
	)
	(wire
		(pts
			(xy 167.64 41.91) (xy 186.69 41.91)
		)
		(stroke
			(width 0)
			(type default)
		)
	)
	(wire
		(pts
			(xy 359.41 154.94) (xy 364.49 154.94)
		)
		(stroke
			(width 0)
			(type default)
		)
	)
	(wire
		(pts
			(xy 138.43 39.37) (xy 138.43 67.31)
		)
		(stroke
			(width 0)
			(type default)
		)
	)
	(wire
		(pts
			(xy 344.17 149.86) (xy 359.41 149.86)
		)
		(stroke
			(width 0)
			(type default)
		)
	)
	(wire
		(pts
			(xy 349.25 154.94) (xy 359.41 154.94)
		)
		(stroke
			(width 0)
			(type default)
		)
	)
	(wire
		(pts
			(xy 344.17 48.26) (xy 364.49 48.26)
		)
		(stroke
			(width 0)
			(type default)
		)
	)
	(wire
		(pts
			(xy 46.99 160.02) (xy 30.48 160.02)
		)
		(stroke
			(width 0)
			(type default)
		)
	)
	(wire
		(pts
			(xy 86.36 231.14) (xy 88.9 231.14)
		)
		(stroke
			(width 0)
			(type default)
		)
	)
	(wire
		(pts
			(xy 82.55 86.36) (xy 97.79 86.36)
		)
		(stroke
			(width 0)
			(type default)
		)
	)
	(wire
		(pts
			(xy 81.28 139.7) (xy 81.28 140.97)
		)
		(stroke
			(width 0)
			(type default)
		)
	)
	(wire
		(pts
			(xy 361.95 99.06) (xy 364.49 99.06)
		)
		(stroke
			(width 0)
			(type default)
		)
	)
	(wire
		(pts
			(xy 140.97 96.52) (xy 140.97 119.38)
		)
		(stroke
			(width 0)
			(type default)
		)
	)
	(wire
		(pts
			(xy 218.44 248.92) (xy 218.44 254)
		)
		(stroke
			(width 0)
			(type default)
		)
	)
	(wire
		(pts
			(xy 175.26 215.9) (xy 201.93 215.9)
		)
		(stroke
			(width 0)
			(type default)
		)
	)
	(wire
		(pts
			(xy 284.48 53.34) (xy 284.48 60.96)
		)
		(stroke
			(width 0)
			(type default)
		)
	)
	(wire
		(pts
			(xy 157.48 64.77) (xy 140.97 64.77)
		)
		(stroke
			(width 0)
			(type default)
		)
	)
	(wire
		(pts
			(xy 284.48 99.06) (xy 284.48 106.68)
		)
		(stroke
			(width 0)
			(type default)
		)
	)
	(wire
		(pts
			(xy 82.55 93.98) (xy 97.79 93.98)
		)
		(stroke
			(width 0)
			(type default)
		)
	)
	(wire
		(pts
			(xy 35.56 93.98) (xy 35.56 91.44)
		)
		(stroke
			(width 0)
			(type default)
		)
	)
	(wire
		(pts
			(xy 363.22 214.63) (xy 381 214.63)
		)
		(stroke
			(width 0)
			(type default)
		)
	)
	(wire
		(pts
			(xy 281.94 88.9) (xy 287.02 88.9)
		)
		(stroke
			(width 0)
			(type default)
		)
	)
	(wire
		(pts
			(xy 193.04 243.84) (xy 193.04 233.68)
		)
		(stroke
			(width 0)
			(type default)
		)
	)
	(wire
		(pts
			(xy 266.7 161.29) (xy 266.7 162.56)
		)
		(stroke
			(width 0)
			(type default)
		)
	)
	(polyline
		(pts
			(xy 190.5 29.21) (xy 190.5 48.26)
		)
		(stroke
			(width 0)
			(type solid)
		)
	)
	(wire
		(pts
			(xy 361.95 163.83) (xy 361.95 162.56)
		)
		(stroke
			(width 0)
			(type default)
		)
	)
	(wire
		(pts
			(xy 67.31 153.67) (xy 78.74 153.67)
		)
		(stroke
			(width 0)
			(type default)
		)
	)
	(wire
		(pts
			(xy 361.95 160.02) (xy 361.95 162.56)
		)
		(stroke
			(width 0)
			(type default)
		)
	)
	(wire
		(pts
			(xy 86.36 151.13) (xy 86.36 162.56)
		)
		(stroke
			(width 0)
			(type default)
		)
	)
	(wire
		(pts
			(xy 83.82 233.68) (xy 76.2 233.68)
		)
		(stroke
			(width 0)
			(type default)
		)
	)
	(wire
		(pts
			(xy 62.23 48.26) (xy 59.69 48.26)
		)
		(stroke
			(width 0)
			(type default)
		)
	)
	(wire
		(pts
			(xy 44.45 139.7) (xy 44.45 140.97)
		)
		(stroke
			(width 0)
			(type default)
		)
	)
	(wire
		(pts
			(xy 334.01 134.62) (xy 350.52 134.62)
		)
		(stroke
			(width 0)
			(type default)
		)
	)
	(wire
		(pts
			(xy 283.21 132.08) (xy 287.02 132.08)
		)
		(stroke
			(width 0)
			(type default)
		)
	)
	(wire
		(pts
			(xy 140.97 41.91) (xy 157.48 41.91)
		)
		(stroke
			(width 0)
			(type default)
		)
	)
	(wire
		(pts
			(xy 140.97 119.38) (xy 157.48 119.38)
		)
		(stroke
			(width 0)
			(type default)
		)
	)
	(wire
		(pts
			(xy 341.63 238.76) (xy 341.63 227.33)
		)
		(stroke
			(width 0)
			(type default)
		)
	)
	(wire
		(pts
			(xy 167.64 39.37) (xy 186.69 39.37)
		)
		(stroke
			(width 0)
			(type default)
		)
	)
	(wire
		(pts
			(xy 35.56 74.93) (xy 35.56 77.47)
		)
		(stroke
			(width 0)
			(type default)
		)
	)
	(wire
		(pts
			(xy 342.9 238.76) (xy 341.63 238.76)
		)
		(stroke
			(width 0)
			(type default)
		)
	)
	(wire
		(pts
			(xy 193.04 201.93) (xy 185.42 201.93)
		)
		(stroke
			(width 0)
			(type default)
		)
	)
	(wire
		(pts
			(xy 185.42 201.93) (xy 185.42 203.2)
		)
		(stroke
			(width 0)
			(type default)
		)
	)
	(wire
		(pts
			(xy 281.94 154.94) (xy 281.94 157.48)
		)
		(stroke
			(width 0)
			(type default)
		)
	)
	(wire
		(pts
			(xy 44.45 86.36) (xy 62.23 86.36)
		)
		(stroke
			(width 0)
			(type default)
		)
	)
	(wire
		(pts
			(xy 361.95 68.58) (xy 364.49 68.58)
		)
		(stroke
			(width 0)
			(type default)
		)
	)
	(polyline
		(pts
			(xy 180.34 162.56) (xy 129.54 162.56)
		)
		(stroke
			(width 0)
			(type solid)
		)
	)
	(polyline
		(pts
			(xy 207.01 12.7) (xy 207.01 180.34)
		)
		(stroke
			(width 0)
			(type default)
		)
	)
	(wire
		(pts
			(xy 246.38 149.86) (xy 266.7 149.86)
		)
		(stroke
			(width 0)
			(type default)
		)
	)
	(wire
		(pts
			(xy 83.82 139.7) (xy 83.82 140.97)
		)
		(stroke
			(width 0)
			(type default)
		)
	)
	(polyline
		(pts
			(xy 129.54 146.05) (xy 180.34 146.05)
		)
		(stroke
			(width 0)
			(type solid)
		)
	)
	(wire
		(pts
			(xy 30.48 162.56) (xy 49.53 162.56)
		)
		(stroke
			(width 0)
			(type default)
		)
	)
	(wire
		(pts
			(xy 372.11 195.58) (xy 372.11 196.85)
		)
		(stroke
			(width 0)
			(type default)
		)
	)
	(wire
		(pts
			(xy 349.25 161.29) (xy 349.25 162.56)
		)
		(stroke
			(width 0)
			(type default)
		)
	)
	(wire
		(pts
			(xy 66.04 215.9) (xy 66.04 248.92)
		)
		(stroke
			(width 0)
			(type default)
		)
	)
	(wire
		(pts
			(xy 341.63 111.76) (xy 364.49 111.76)
		)
		(stroke
			(width 0)
			(type default)
		)
	)
	(wire
		(pts
			(xy 334.01 196.85) (xy 334.01 198.12)
		)
		(stroke
			(width 0)
			(type default)
		)
	)
	(wire
		(pts
			(xy 281.94 93.98) (xy 287.02 93.98)
		)
		(stroke
			(width 0)
			(type default)
		)
	)
	(wire
		(pts
			(xy 41.91 140.97) (xy 41.91 139.7)
		)
		(stroke
			(width 0)
			(type default)
		)
	)
	(wire
		(pts
			(xy 35.56 135.89) (xy 35.56 139.7)
		)
		(stroke
			(width 0)
			(type default)
		)
	)
	(wire
		(pts
			(xy 31.75 63.5) (xy 35.56 63.5)
		)
		(stroke
			(width 0)
			(type default)
		)
	)
	(wire
		(pts
			(xy 82.55 71.12) (xy 92.71 71.12)
		)
		(stroke
			(width 0)
			(type default)
		)
	)
	(wire
		(pts
			(xy 372.11 196.85) (xy 372.11 198.12)
		)
		(stroke
			(width 0)
			(type default)
		)
	)
	(wire
		(pts
			(xy 360.68 104.14) (xy 364.49 104.14)
		)
		(stroke
			(width 0)
			(type default)
		)
	)
	(wire
		(pts
			(xy 360.68 134.62) (xy 364.49 134.62)
		)
		(stroke
			(width 0)
			(type default)
		)
	)
	(wire
		(pts
			(xy 26.67 129.54) (xy 26.67 130.81)
		)
		(stroke
			(width 0)
			(type default)
		)
	)
	(polyline
		(pts
			(xy 207.01 180.34) (xy 299.72 180.34)
		)
		(stroke
			(width 0)
			(type default)
		)
	)
	(wire
		(pts
			(xy 218.44 215.9) (xy 218.44 220.98)
		)
		(stroke
			(width 0)
			(type default)
		)
	)
	(wire
		(pts
			(xy 283.21 137.16) (xy 287.02 137.16)
		)
		(stroke
			(width 0)
			(type default)
		)
	)
	(wire
		(pts
			(xy 334.01 132.08) (xy 350.52 132.08)
		)
		(stroke
			(width 0)
			(type default)
		)
	)
	(wire
		(pts
			(xy 49.53 44.45) (xy 49.53 45.72)
		)
		(stroke
			(width 0)
			(type default)
		)
	)
	(wire
		(pts
			(xy 341.63 196.85) (xy 334.01 196.85)
		)
		(stroke
			(width 0)
			(type default)
		)
	)
	(wire
		(pts
			(xy 123.19 213.36) (xy 123.19 214.63)
		)
		(stroke
			(width 0)
			(type default)
		)
	)
	(wire
		(pts
			(xy 344.17 88.9) (xy 364.49 88.9)
		)
		(stroke
			(width 0)
			(type default)
		)
	)
	(wire
		(pts
			(xy 281.94 104.14) (xy 287.02 104.14)
		)
		(stroke
			(width 0)
			(type default)
		)
	)
	(wire
		(pts
			(xy 83.82 160.02) (xy 67.31 160.02)
		)
		(stroke
			(width 0)
			(type default)
		)
	)
	(wire
		(pts
			(xy 281.94 101.6) (xy 287.02 101.6)
		)
		(stroke
			(width 0)
			(type default)
		)
	)
	(wire
		(pts
			(xy 361.95 106.68) (xy 364.49 106.68)
		)
		(stroke
			(width 0)
			(type default)
		)
	)
	(wire
		(pts
			(xy 107.95 246.38) (xy 123.19 246.38)
		)
		(stroke
			(width 0)
			(type default)
		)
	)
	(wire
		(pts
			(xy 217.17 210.82) (xy 232.41 210.82)
		)
		(stroke
			(width 0)
			(type default)
		)
	)
	(wire
		(pts
			(xy 175.26 200.66) (xy 175.26 203.2)
		)
		(stroke
			(width 0)
			(type default)
		)
	)
	(wire
		(pts
			(xy 83.82 139.7) (xy 86.36 139.7)
		)
		(stroke
			(width 0)
			(type default)
		)
	)
	(wire
		(pts
			(xy 363.22 212.09) (xy 381 212.09)
		)
		(stroke
			(width 0)
			(type default)
		)
	)
	(wire
		(pts
			(xy 83.82 210.82) (xy 92.71 210.82)
		)
		(stroke
			(width 0)
			(type default)
		)
	)
	(wire
		(pts
			(xy 361.95 106.68) (xy 361.95 160.02)
		)
		(stroke
			(width 0)
			(type default)
		)
	)
	(wire
		(pts
			(xy 134.62 44.45) (xy 144.78 44.45)
		)
		(stroke
			(width 0)
			(type default)
		)
	)
	(wire
		(pts
			(xy 167.64 119.38) (xy 186.69 119.38)
		)
		(stroke
			(width 0)
			(type default)
		)
	)
	(wire
		(pts
			(xy 264.16 116.84) (xy 287.02 116.84)
		)
		(stroke
			(width 0)
			(type default)
		)
	)
	(wire
		(pts
			(xy 82.55 55.88) (xy 92.71 55.88)
		)
		(stroke
			(width 0)
			(type default)
		)
	)
	(wire
		(pts
			(xy 364.49 238.76) (xy 364.49 227.33)
		)
		(stroke
			(width 0)
			(type default)
		)
	)
	(wire
		(pts
			(xy 67.31 156.21) (xy 81.28 156.21)
		)
		(stroke
			(width 0)
			(type default)
		)
	)
	(wire
		(pts
			(xy 266.7 149.86) (xy 266.7 156.21)
		)
		(stroke
			(width 0)
			(type default)
		)
	)
	(wire
		(pts
			(xy 76.2 200.66) (xy 76.2 201.93)
		)
		(stroke
			(width 0)
			(type default)
		)
	)
	(wire
		(pts
			(xy 266.7 38.1) (xy 287.02 38.1)
		)
		(stroke
			(width 0)
			(type default)
		)
	)
	(wire
		(pts
			(xy 284.48 60.96) (xy 284.48 68.58)
		)
		(stroke
			(width 0)
			(type default)
		)
	)
	(wire
		(pts
			(xy 360.68 137.16) (xy 364.49 137.16)
		)
		(stroke
			(width 0)
			(type default)
		)
	)
	(polyline
		(pts
			(xy 107.95 12.7) (xy 107.95 180.34)
		)
		(stroke
			(width 0)
			(type default)
		)
	)
	(wire
		(pts
			(xy 64.77 135.89) (xy 64.77 139.7)
		)
		(stroke
			(width 0)
			(type default)
		)
	)
	(wire
		(pts
			(xy 246.38 149.86) (xy 246.38 156.21)
		)
		(stroke
			(width 0)
			(type default)
		)
	)
	(wire
		(pts
			(xy 266.7 35.56) (xy 287.02 35.56)
		)
		(stroke
			(width 0)
			(type default)
		)
	)
	(wire
		(pts
			(xy 83.82 243.84) (xy 83.82 233.68)
		)
		(stroke
			(width 0)
			(type default)
		)
	)
	(wire
		(pts
			(xy 167.64 101.6) (xy 186.69 101.6)
		)
		(stroke
			(width 0)
			(type default)
		)
	)
	(wire
		(pts
			(xy 372.11 203.2) (xy 372.11 204.47)
		)
		(stroke
			(width 0)
			(type default)
		)
	)
	(wire
		(pts
			(xy 256.54 132.08) (xy 273.05 132.08)
		)
		(stroke
			(width 0)
			(type default)
		)
	)
	(wire
		(pts
			(xy 82.55 96.52) (xy 97.79 96.52)
		)
		(stroke
			(width 0)
			(type default)
		)
	)
	(wire
		(pts
			(xy 341.63 209.55) (xy 341.63 196.85)
		)
		(stroke
			(width 0)
			(type default)
		)
	)
	(wire
		(pts
			(xy 287.02 152.4) (xy 281.94 152.4)
		)
		(stroke
			(width 0)
			(type default)
		)
	)
	(wire
		(pts
			(xy 72.39 129.54) (xy 72.39 130.81)
		)
		(stroke
			(width 0)
			(type default)
		)
	)
	(wire
		(pts
			(xy 82.55 50.8) (xy 92.71 50.8)
		)
		(stroke
			(width 0)
			(type default)
		)
	)
	(wire
		(pts
			(xy 287.02 53.34) (xy 284.48 53.34)
		)
		(stroke
			(width 0)
			(type default)
		)
	)
	(wire
		(pts
			(xy 323.85 161.29) (xy 323.85 162.56)
		)
		(stroke
			(width 0)
			(type default)
		)
	)
	(wire
		(pts
			(xy 44.45 139.7) (xy 46.99 139.7)
		)
		(stroke
			(width 0)
			(type default)
		)
	)
	(wire
		(pts
			(xy 372.11 227.33) (xy 372.11 228.6)
		)
		(stroke
			(width 0)
			(type default)
		)
	)
	(wire
		(pts
			(xy 334.01 195.58) (xy 334.01 196.85)
		)
		(stroke
			(width 0)
			(type default)
		)
	)
	(wire
		(pts
			(xy 147.32 101.6) (xy 157.48 101.6)
		)
		(stroke
			(width 0)
			(type default)
		)
	)
	(wire
		(pts
			(xy 363.22 238.76) (xy 364.49 238.76)
		)
		(stroke
			(width 0)
			(type default)
		)
	)
	(polyline
		(pts
			(xy 261.62 41.91) (xy 261.62 59.69)
		)
		(stroke
			(width 0)
			(type solid)
		)
	)
	(wire
		(pts
			(xy 30.48 156.21) (xy 44.45 156.21)
		)
		(stroke
			(width 0)
			(type default)
		)
	)
	(wire
		(pts
			(xy 92.71 246.38) (xy 86.36 246.38)
		)
		(stroke
			(width 0)
			(type default)
		)
	)
	(polyline
		(pts
			(xy 129.54 139.7) (xy 129.54 162.56)
		)
		(stroke
			(width 0)
			(type solid)
		)
	)
	(wire
		(pts
			(xy 361.95 60.96) (xy 364.49 60.96)
		)
		(stroke
			(width 0)
			(type default)
		)
	)
	(wire
		(pts
			(xy 344.17 45.72) (xy 364.49 45.72)
		)
		(stroke
			(width 0)
			(type default)
		)
	)
	(wire
		(pts
			(xy 82.55 73.66) (xy 92.71 73.66)
		)
		(stroke
			(width 0)
			(type default)
		)
	)
	(wire
		(pts
			(xy 364.49 53.34) (xy 361.95 53.34)
		)
		(stroke
			(width 0)
			(type default)
		)
	)
	(wire
		(pts
			(xy 232.41 213.36) (xy 232.41 214.63)
		)
		(stroke
			(width 0)
			(type default)
		)
	)
	(wire
		(pts
			(xy 246.38 167.64) (xy 246.38 168.91)
		)
		(stroke
			(width 0)
			(type default)
		)
	)
	(wire
		(pts
			(xy 344.17 161.29) (xy 344.17 162.56)
		)
		(stroke
			(width 0)
			(type default)
		)
	)
	(wire
		(pts
			(xy 281.94 96.52) (xy 287.02 96.52)
		)
		(stroke
			(width 0)
			(type default)
		)
	)
	(wire
		(pts
			(xy 349.25 154.94) (xy 349.25 156.21)
		)
		(stroke
			(width 0)
			(type default)
		)
	)
	(wire
		(pts
			(xy 264.16 111.76) (xy 287.02 111.76)
		)
		(stroke
			(width 0)
			(type default)
		)
	)
	(wire
		(pts
			(xy 281.94 154.94) (xy 287.02 154.94)
		)
		(stroke
			(width 0)
			(type default)
		)
	)
	(wire
		(pts
			(xy 83.82 243.84) (xy 92.71 243.84)
		)
		(stroke
			(width 0)
			(type default)
		)
	)
	(wire
		(pts
			(xy 40.64 60.96) (xy 62.23 60.96)
		)
		(stroke
			(width 0)
			(type default)
		)
	)
	(wire
		(pts
			(xy 167.64 93.98) (xy 186.69 93.98)
		)
		(stroke
			(width 0)
			(type default)
		)
	)
	(polyline
		(pts
			(xy 341.63 41.91) (xy 341.63 59.69)
		)
		(stroke
			(width 0)
			(type solid)
		)
	)
	(wire
		(pts
			(xy 283.21 134.62) (xy 287.02 134.62)
		)
		(stroke
			(width 0)
			(type default)
		)
	)
	(wire
		(pts
			(xy 323.85 167.64) (xy 323.85 168.91)
		)
		(stroke
			(width 0)
			(type default)
		)
	)
	(wire
		(pts
			(xy 193.04 243.84) (xy 201.93 243.84)
		)
		(stroke
			(width 0)
			(type default)
		)
	)
	(wire
		(pts
			(xy 193.04 233.68) (xy 185.42 233.68)
		)
		(stroke
			(width 0)
			(type default)
		)
	)
	(wire
		(pts
			(xy 167.64 64.77) (xy 186.69 64.77)
		)
		(stroke
			(width 0)
			(type default)
		)
	)
	(wire
		(pts
			(xy 363.22 241.3) (xy 381 241.3)
		)
		(stroke
			(width 0)
			(type default)
		)
	)
	(wire
		(pts
			(xy 328.93 161.29) (xy 328.93 162.56)
		)
		(stroke
			(width 0)
			(type default)
		)
	)
	(wire
		(pts
			(xy 217.17 248.92) (xy 218.44 248.92)
		)
		(stroke
			(width 0)
			(type default)
		)
	)
	(wire
		(pts
			(xy 82.55 48.26) (xy 92.71 48.26)
		)
		(stroke
			(width 0)
			(type default)
		)
	)
	(wire
		(pts
			(xy 167.64 99.06) (xy 186.69 99.06)
		)
		(stroke
			(width 0)
			(type default)
		)
	)
	(wire
		(pts
			(xy 175.26 215.9) (xy 175.26 248.92)
		)
		(stroke
			(width 0)
			(type default)
		)
	)
	(wire
		(pts
			(xy 361.95 53.34) (xy 361.95 60.96)
		)
		(stroke
			(width 0)
			(type default)
		)
	)
	(wire
		(pts
			(xy 344.17 149.86) (xy 344.17 156.21)
		)
		(stroke
			(width 0)
			(type default)
		)
	)
	(wire
		(pts
			(xy 359.41 149.86) (xy 364.49 149.86)
		)
		(stroke
			(width 0)
			(type default)
		)
	)
	(wire
		(pts
			(xy 147.32 46.99) (xy 147.32 59.69)
		)
		(stroke
			(width 0)
			(type default)
		)
	)
	(wire
		(pts
			(xy 281.94 50.8) (xy 287.02 50.8)
		)
		(stroke
			(width 0)
			(type default)
		)
	)
	(wire
		(pts
			(xy 167.64 44.45) (xy 186.69 44.45)
		)
		(stroke
			(width 0)
			(type default)
		)
	)
	(wire
		(pts
			(xy 144.78 99.06) (xy 157.48 99.06)
		)
		(stroke
			(width 0)
			(type default)
		)
	)
	(wire
		(pts
			(xy 134.62 46.99) (xy 147.32 46.99)
		)
		(stroke
			(width 0)
			(type default)
		)
	)
	(wire
		(pts
			(xy 340.36 241.3) (xy 342.9 241.3)
		)
		(stroke
			(width 0)
			(type default)
		)
	)
	(wire
		(pts
			(xy 361.95 68.58) (xy 361.95 76.2)
		)
		(stroke
			(width 0)
			(type default)
		)
	)
	(wire
		(pts
			(xy 76.2 208.28) (xy 76.2 209.55)
		)
		(stroke
			(width 0)
			(type default)
		)
	)
	(wire
		(pts
			(xy 82.55 63.5) (xy 92.71 63.5)
		)
		(stroke
			(width 0)
			(type default)
		)
	)
	(wire
		(pts
			(xy 284.48 60.96) (xy 287.02 60.96)
		)
		(stroke
			(width 0)
			(type default)
		)
	)
	(wire
		(pts
			(xy 302.26 149.86) (xy 323.85 149.86)
		)
		(stroke
			(width 0)
			(type default)
		)
	)
	(wire
		(pts
			(xy 44.45 74.93) (xy 44.45 77.47)
		)
		(stroke
			(width 0)
			(type default)
		)
	)
	(wire
		(pts
			(xy 341.63 238.76) (xy 341.63 246.38)
		)
		(stroke
			(width 0)
			(type default)
		)
	)
	(wire
		(pts
			(xy 147.32 59.69) (xy 157.48 59.69)
		)
		(stroke
			(width 0)
			(type default)
		)
	)
	(polyline
		(pts
			(xy 12.7 180.34) (xy 207.01 180.34)
		)
		(stroke
			(width 0)
			(type default)
		)
	)
	(wire
		(pts
			(xy 83.82 201.93) (xy 83.82 210.82)
		)
		(stroke
			(width 0)
			(type default)
		)
	)
	(wire
		(pts
			(xy 361.95 99.06) (xy 361.95 106.68)
		)
		(stroke
			(width 0)
			(type default)
		)
	)
	(wire
		(pts
			(xy 44.45 82.55) (xy 44.45 86.36)
		)
		(stroke
			(width 0)
			(type default)
		)
	)
	(wire
		(pts
			(xy 30.48 153.67) (xy 41.91 153.67)
		)
		(stroke
			(width 0)
			(type default)
		)
	)
	(wire
		(pts
			(xy 364.49 152.4) (xy 359.41 152.4)
		)
		(stroke
			(width 0)
			(type default)
		)
	)
	(wire
		(pts
			(xy 341.63 246.38) (xy 342.9 246.38)
		)
		(stroke
			(width 0)
			(type default)
		)
	)
	(wire
		(pts
			(xy 46.99 139.7) (xy 46.99 140.97)
		)
		(stroke
			(width 0)
			(type default)
		)
	)
	(wire
		(pts
			(xy 360.68 132.08) (xy 364.49 132.08)
		)
		(stroke
			(width 0)
			(type default)
		)
	)
	(wire
		(pts
			(xy 35.56 82.55) (xy 35.56 91.44)
		)
		(stroke
			(width 0)
			(type default)
		)
	)
	(wire
		(pts
			(xy 35.56 139.7) (xy 41.91 139.7)
		)
		(stroke
			(width 0)
			(type default)
		)
	)
	(wire
		(pts
			(xy 185.42 200.66) (xy 185.42 201.93)
		)
		(stroke
			(width 0)
			(type default)
		)
	)
	(wire
		(pts
			(xy 334.01 226.06) (xy 334.01 227.33)
		)
		(stroke
			(width 0)
			(type default)
		)
	)
	(wire
		(pts
			(xy 284.48 160.02) (xy 287.02 160.02)
		)
		(stroke
			(width 0)
			(type default)
		)
	)
	(wire
		(pts
			(xy 134.62 93.98) (xy 138.43 93.98)
		)
		(stroke
			(width 0)
			(type default)
		)
	)
	(polyline
		(pts
			(xy 299.72 180.34) (xy 407.67 180.34)
		)
		(stroke
			(width 0)
			(type default)
		)
	)
	(wire
		(pts
			(xy 271.78 154.94) (xy 281.94 154.94)
		)
		(stroke
			(width 0)
			(type default)
		)
	)
	(wire
		(pts
			(xy 138.43 93.98) (xy 157.48 93.98)
		)
		(stroke
			(width 0)
			(type default)
		)
	)
	(wire
		(pts
			(xy 251.46 154.94) (xy 271.78 154.94)
		)
		(stroke
			(width 0)
			(type default)
		)
	)
	(wire
		(pts
			(xy 341.63 209.55) (xy 341.63 217.17)
		)
		(stroke
			(width 0)
			(type default)
		)
	)
	(polyline
		(pts
			(xy 154.94 139.7) (xy 154.94 162.56)
		)
		(stroke
			(width 0)
			(type solid)
		)
	)
	(wire
		(pts
			(xy 66.04 200.66) (xy 66.04 203.2)
		)
		(stroke
			(width 0)
			(type default)
		)
	)
	(wire
		(pts
			(xy 281.94 43.18) (xy 287.02 43.18)
		)
		(stroke
			(width 0)
			(type default)
		)
	)
	(wire
		(pts
			(xy 328.93 154.94) (xy 349.25 154.94)
		)
		(stroke
			(width 0)
			(type default)
		)
	)
	(wire
		(pts
			(xy 281.94 152.4) (xy 281.94 149.86)
		)
		(stroke
			(width 0)
			(type default)
		)
	)
	(wire
		(pts
			(xy 140.97 96.52) (xy 157.48 96.52)
		)
		(stroke
			(width 0)
			(type default)
		)
	)
	(wire
		(pts
			(xy 185.42 233.68) (xy 185.42 234.95)
		)
		(stroke
			(width 0)
			(type default)
		)
	)
	(wire
		(pts
			(xy 44.45 151.13) (xy 44.45 156.21)
		)
		(stroke
			(width 0)
			(type default)
		)
	)
	(wire
		(pts
			(xy 341.63 116.84) (xy 364.49 116.84)
		)
		(stroke
			(width 0)
			(type default)
		)
	)
	(wire
		(pts
			(xy 167.64 114.3) (xy 186.69 114.3)
		)
		(stroke
			(width 0)
			(type default)
		)
	)
	(wire
		(pts
			(xy 283.21 129.54) (xy 287.02 129.54)
		)
		(stroke
			(width 0)
			(type default)
		)
	)
	(wire
		(pts
			(xy 147.32 101.6) (xy 147.32 114.3)
		)
		(stroke
			(width 0)
			(type default)
		)
	)
	(text "CONNECTOR J8\n"
		(exclude_from_sim no)
		(at 155.575 144.78 0)
		(effects
			(font
				(size 2 2)
				(thickness 0.4)
				(bold yes)
			)
			(justify left bottom)
		)
	)
	(text "CSI2 x2"
		(exclude_from_sim no)
		(at 261.62 100.33 90)
		(effects
			(font
				(size 1.27 1.27)
			)
			(justify left bottom)
		)
	)
	(text "CSI0x2 CSI2x2"
		(exclude_from_sim no)
		(at 130.175 161.29 0)
		(effects
			(font
				(size 2 2)
			)
			(justify left bottom)
		)
	)
	(text "CONNECTOR J7"
		(exclude_from_sim no)
		(at 130.175 144.78 0)
		(effects
			(font
				(size 2 2)
				(thickness 0.4)
				(bold yes)
			)
			(justify left bottom)
		)
	)
	(text "CSI1x2"
		(exclude_from_sim no)
		(at 160.655 157.48 0)
		(effects
			(font
				(size 2 2)
			)
			(justify left bottom)
		)
	)
	(text "NONE"
		(exclude_from_sim no)
		(at 161.925 149.86 0)
		(effects
			(font
				(size 2 2)
			)
			(justify left bottom)
		)
	)
	(text "CSI3x2"
		(exclude_from_sim no)
		(at 160.655 153.67 0)
		(effects
			(font
				(size 2 2)
			)
			(justify left bottom)
		)
	)
	(text "TO CONNECTOR J7"
		(exclude_from_sim no)
		(at 192.405 69.215 90)
		(effects
			(font
				(size 1.27 1.27)
			)
			(justify left bottom)
		)
	)
	(text "CSI3x2 CSI1x2"
		(exclude_from_sim no)
		(at 155.575 161.29 0)
		(effects
			(font
				(size 2 2)
			)
			(justify left bottom)
		)
	)
	(text "CSI0 x2"
		(exclude_from_sim no)
		(at 260.985 54.61 90)
		(effects
			(font
				(size 1.27 1.27)
			)
			(justify left bottom)
		)
	)
	(text "CSI3 x2"
		(exclude_from_sim no)
		(at 340.36 100.33 90)
		(effects
			(font
				(size 1.27 1.27)
			)
			(justify left bottom)
		)
	)
	(text "TO CONNECTOR J8\n"
		(exclude_from_sim no)
		(at 192.405 47.625 90)
		(effects
			(font
				(size 1.27 1.27)
			)
			(justify left bottom)
		)
	)
	(text "CSI0x4 CSI2x2"
		(exclude_from_sim no)
		(at 130.175 153.67 0)
		(effects
			(font
				(size 2 2)
			)
			(justify left bottom)
		)
	)
	(text "Power switches"
		(exclude_from_sim no)
		(at 119.38 189.865 0)
		(effects
			(font
				(size 4 4)
				(thickness 0.8)
				(bold yes)
			)
			(justify left bottom)
		)
	)
	(text "CSI2 x4"
		(exclude_from_sim no)
		(at 257.81 95.25 90)
		(effects
			(font
				(size 1.27 1.27)
			)
			(justify left bottom)
		)
	)
	(text "CSI0x4 CSI2x4"
		(exclude_from_sim no)
		(at 130.175 149.86 0)
		(effects
			(font
				(size 2 2)
			)
			(justify left bottom)
		)
	)
	(text "CSI1 x2"
		(exclude_from_sim no)
		(at 341.63 54.61 90)
		(effects
			(font
				(size 1.27 1.27)
			)
			(justify left bottom)
		)
	)
	(text "AVAILABLE CSI CONFIGURATIONS:"
		(exclude_from_sim no)
		(at 128.905 138.43 0)
		(effects
			(font
				(size 2 2)
				(thickness 0.4)
				(bold yes)
			)
			(justify left bottom)
		)
	)
	(text "CSI Mux\n"
		(exclude_from_sim no)
		(at 143.51 21.59 0)
		(effects
			(font
				(size 4 4)
				(thickness 0.8)
				(bold yes)
			)
			(justify left bottom)
		)
	)
	(text "CSI connector J7"
		(exclude_from_sim no)
		(at 247.65 21.59 0)
		(effects
			(font
				(size 4 4)
				(thickness 0.8)
				(bold yes)
			)
			(justify left bottom)
		)
	)
	(text "CSI0x2 CSI2x4"
		(exclude_from_sim no)
		(at 130.175 157.48 0)
		(effects
			(font
				(size 2 2)
			)
			(justify left bottom)
		)
	)
	(text "TO CONNECTOR J8\n"
		(exclude_from_sim no)
		(at 192.405 102.235 90)
		(effects
			(font
				(size 1.27 1.27)
			)
			(justify left bottom)
		)
	)
	(text "TO CONNECTOR J7"
		(exclude_from_sim no)
		(at 192.405 123.825 90)
		(effects
			(font
				(size 1.27 1.27)
			)
			(justify left bottom)
		)
	)
	(text "CSI0 x4"
		(exclude_from_sim no)
		(at 257.175 49.53 90)
		(effects
			(font
				(size 1.27 1.27)
			)
			(justify left bottom)
		)
	)
	(text "I2C Mux"
		(exclude_from_sim no)
		(at 46.99 21.59 0)
		(effects
			(font
				(size 4 4)
				(thickness 0.8)
				(bold yes)
			)
			(justify left bottom)
		)
	)
	(text "CSI connector J8"
		(exclude_from_sim no)
		(at 334.01 21.59 0)
		(effects
			(font
				(size 4 4)
				(thickness 0.8)
				(bold yes)
			)
			(justify left bottom)
		)
	)
	(text "ALL SWITCHES\n1.5A CURRENT LIMIT"
		(exclude_from_sim no)
		(at 134.62 198.755 0)
		(effects
			(font
				(size 1.27 1.27)
			)
			(justify left bottom)
		)
	)
	(text "Level shifters"
		(exclude_from_sim no)
		(at 331.47 187.96 0)
		(effects
			(font
				(size 4 4)
				(thickness 0.8)
				(bold yes)
			)
			(justify left bottom)
		)
	)
	(label "SDA_CAM0"
		(at 92.71 48.26 180)
		(effects
			(font
				(size 1.27 1.27)
			)
			(justify right bottom)
		)
	)
	(label "VSYNC_CAM1_3V3"
		(at 264.16 116.84 0)
		(effects
			(font
				(size 1.27 1.27)
			)
			(justify left bottom)
		)
	)
	(label "CSIB_3V3"
		(at 232.41 243.84 180)
		(effects
			(font
				(size 1.27 1.27)
			)
			(justify right bottom)
		)
	)
	(label "CSI3_1_D0_P"
		(at 186.69 96.52 180)
		(effects
			(font
				(size 1.27 1.27)
			)
			(justify right bottom)
		)
	)
	(label "SDA_CAM2"
		(at 67.31 162.56 0)
		(effects
			(font
				(size 1.27 1.27)
			)
			(justify left bottom)
		)
	)
	(label "CSI1_0_D1_P"
		(at 266.7 35.56 0)
		(effects
			(font
				(size 1.27 1.27)
			)
			(justify left bottom)
		)
	)
	(label "CSI1_0_D1_N"
		(at 186.69 59.69 180)
		(effects
			(font
				(size 1.27 1.27)
			)
			(justify right bottom)
		)
	)
	(label "MUX_I2C_5_SCL"
		(at 82.55 88.9 0)
		(effects
			(font
				(size 1.27 1.27)
			)
			(justify left bottom)
		)
	)
	(label "SCL_CAM0"
		(at 256.54 132.08 0)
		(effects
			(font
				(size 1.27 1.27)
			)
			(justify left bottom)
		)
	)
	(label "VSYNC_CAM0_3V3"
		(at 381 212.09 180)
		(effects
			(font
				(size 1.27 1.27)
			)
			(justify right bottom)
		)
	)
	(label "CSIA_3V3_ISET"
		(at 123.19 246.38 180)
		(effects
			(font
				(size 1.27 1.27)
			)
			(justify right bottom)
		)
	)
	(label "CSI3_0_D1_P"
		(at 266.7 81.28 0)
		(effects
			(font
				(size 1.27 1.27)
			)
			(justify left bottom)
		)
	)
	(label "SDA_CAM1"
		(at 256.54 134.62 0)
		(effects
			(font
				(size 1.27 1.27)
			)
			(justify left bottom)
		)
	)
	(label "CSI3_0_D1_N"
		(at 186.69 116.84 180)
		(effects
			(font
				(size 1.27 1.27)
			)
			(justify right bottom)
		)
	)
	(label "CSIA_3V3"
		(at 123.19 243.84 180)
		(effects
			(font
				(size 1.27 1.27)
			)
			(justify right bottom)
		)
	)
	(label "CSIA_I2C_VCC"
		(at 49.53 139.7 180)
		(effects
			(font
				(size 1.27 1.27)
			)
			(justify right bottom)
		)
	)
	(label "MUX_I2C_7_SCL"
		(at 82.55 104.14 0)
		(effects
			(font
				(size 1.27 1.27)
			)
			(justify left bottom)
		)
	)
	(label "VSYNC_CAM3_3V3"
		(at 341.63 116.84 0)
		(effects
			(font
				(size 1.27 1.27)
			)
			(justify left bottom)
		)
	)
	(label "SDA_CAM2"
		(at 334.01 129.54 0)
		(effects
			(font
				(size 1.27 1.27)
			)
			(justify left bottom)
		)
	)
	(label "CSIA_5V"
		(at 123.19 210.82 180)
		(effects
			(font
				(size 1.27 1.27)
			)
			(justify right bottom)
		)
	)
	(label "SCL_CAM1"
		(at 92.71 58.42 180)
		(effects
			(font
				(size 1.27 1.27)
			)
			(justify right bottom)
		)
	)
	(label "CSI1_0_D1_N"
		(at 266.7 33.02 0)
		(effects
			(font
				(size 1.27 1.27)
			)
			(justify left bottom)
		)
	)
	(label "SDA_CAM3"
		(at 92.71 71.12 180)
		(effects
			(font
				(size 1.27 1.27)
			)
			(justify right bottom)
		)
	)
	(label "MUX_I2C_6_SDA"
		(at 82.55 93.98 0)
		(effects
			(font
				(size 1.27 1.27)
			)
			(justify left bottom)
		)
	)
	(label "CSI1_0_D0_N"
		(at 186.69 64.77 180)
		(effects
			(font
				(size 1.27 1.27)
			)
			(justify right bottom)
		)
	)
	(label "SDA_CAM1"
		(at 92.71 55.88 180)
		(effects
			(font
				(size 1.27 1.27)
			)
			(justify right bottom)
		)
	)
	(label "CSI1_0_D0_P"
		(at 186.69 67.31 180)
		(effects
			(font
				(size 1.27 1.27)
			)
			(justify right bottom)
		)
	)
	(label "VSYNC_CAM2_3V3"
		(at 341.63 111.76 0)
		(effects
			(font
				(size 1.27 1.27)
			)
			(justify left bottom)
		)
	)
	(label "CSI1_1_D0_P"
		(at 344.17 50.8 0)
		(effects
			(font
				(size 1.27 1.27)
			)
			(justify left bottom)
		)
	)
	(label "CSI3_1_D0_P"
		(at 344.17 96.52 0)
		(effects
			(font
				(size 1.27 1.27)
			)
			(justify left bottom)
		)
	)
	(label "CSIB_3V3_ISET"
		(at 232.41 246.38 180)
		(effects
			(font
				(size 1.27 1.27)
			)
			(justify right bottom)
		)
	)
	(label "MUX_I2C_4_SDA"
		(at 82.55 78.74 0)
		(effects
			(font
				(size 1.27 1.27)
			)
			(justify left bottom)
		)
	)
	(label "CSIB_3V3"
		(at 302.26 149.86 0)
		(effects
			(font
				(size 1.27 1.27)
			)
			(justify left bottom)
		)
	)
	(label "CSIB_I2C_VCC"
		(at 86.36 139.7 180)
		(effects
			(font
				(size 1.27 1.27)
			)
			(justify right bottom)
		)
	)
	(label "CSI3_0_D1_P"
		(at 186.69 114.3 180)
		(effects
			(font
				(size 1.27 1.27)
			)
			(justify right bottom)
		)
	)
	(label "CSI1_1_D1_N"
		(at 186.69 46.99 180)
		(effects
			(font
				(size 1.27 1.27)
			)
			(justify right bottom)
		)
	)
	(label "CSI3_1_D1_P"
		(at 186.69 101.6 180)
		(effects
			(font
				(size 1.27 1.27)
			)
			(justify right bottom)
		)
	)
	(label "SDA_CAM3"
		(at 334.01 134.62 0)
		(effects
			(font
				(size 1.27 1.27)
			)
			(justify left bottom)
		)
	)
	(label "CSI1_0_D0_P"
		(at 266.7 40.64 0)
		(effects
			(font
				(size 1.27 1.27)
			)
			(justify left bottom)
		)
	)
	(label "CSI3_0_D0_N"
		(at 266.7 83.82 0)
		(effects
			(font
				(size 1.27 1.27)
			)
			(justify left bottom)
		)
	)
	(label "CSI3_0_D0_N"
		(at 186.69 121.92 180)
		(effects
			(font
				(size 1.27 1.27)
			)
			(justify right bottom)
		)
	)
	(label "CSIB_5V"
		(at 302.26 154.94 0)
		(effects
			(font
				(size 1.27 1.27)
			)
			(justify left bottom)
		)
	)
	(label "SDA_CAM0"
		(at 256.54 129.54 0)
		(effects
			(font
				(size 1.27 1.27)
			)
			(justify left bottom)
		)
	)
	(label "CSIA_5V_ISET"
		(at 123.19 213.36 180)
		(effects
			(font
				(size 1.27 1.27)
			)
			(justify right bottom)
		)
	)
	(label "SCL_CAM0"
		(at 30.48 160.02 0)
		(effects
			(font
				(size 1.27 1.27)
			)
			(justify left bottom)
		)
	)
	(label "CSI1_1_D1_N"
		(at 344.17 43.18 0)
		(effects
			(font
				(size 1.27 1.27)
			)
			(justify left bottom)
		)
	)
	(label "I2C_MUX_A0"
		(at 46.99 91.44 0)
		(effects
			(font
				(size 1.27 1.27)
			)
			(justify left bottom)
		)
	)
	(label "CSIB_5V"
		(at 232.41 210.82 180)
		(effects
			(font
				(size 1.27 1.27)
			)
			(justify right bottom)
		)
	)
	(label "SDA_CAM2"
		(at 92.71 63.5 180)
		(effects
			(font
				(size 1.27 1.27)
			)
			(justify right bottom)
		)
	)
	(label "SCL_CAM0"
		(at 92.71 50.8 180)
		(effects
			(font
				(size 1.27 1.27)
			)
			(justify right bottom)
		)
	)
	(label "SDA_CAM1"
		(at 30.48 156.21 0)
		(effects
			(font
				(size 1.27 1.27)
			)
			(justify left bottom)
		)
	)
	(label "CSI3_1_D1_N"
		(at 186.69 99.06 180)
		(effects
			(font
				(size 1.27 1.27)
			)
			(justify right bottom)
		)
	)
	(label "I2C_MUX_RESET"
		(at 46.99 86.36 0)
		(effects
			(font
				(size 1.27 1.27)
			)
			(justify left bottom)
		)
	)
	(label "I2C_MUX_SCL"
		(at 60.96 63.5 180)
		(effects
			(font
				(size 1.27 1.27)
			)
			(justify right bottom)
		)
	)
	(label "MUX_I2C_7_SDA"
		(at 82.55 101.6 0)
		(effects
			(font
				(size 1.27 1.27)
			)
			(justify left bottom)
		)
	)
	(label "SCL_CAM2"
		(at 67.31 160.02 0)
		(effects
			(font
				(size 1.27 1.27)
			)
			(justify left bottom)
		)
	)
	(label "CSIB_5V_ISET"
		(at 232.41 213.36 180)
		(effects
			(font
				(size 1.27 1.27)
			)
			(justify right bottom)
		)
	)
	(label "MUX_I2C_6_SCL"
		(at 82.55 96.52 0)
		(effects
			(font
				(size 1.27 1.27)
			)
			(justify left bottom)
		)
	)
	(label "SCL_CAM3"
		(at 67.31 153.67 0)
		(effects
			(font
				(size 1.27 1.27)
			)
			(justify left bottom)
		)
	)
	(label "CSI3_0_D0_P"
		(at 266.7 86.36 0)
		(effects
			(font
				(size 1.27 1.27)
			)
			(justify left bottom)
		)
	)
	(label "CSI1_1_D1_P"
		(at 344.17 45.72 0)
		(effects
			(font
				(size 1.27 1.27)
			)
			(justify left bottom)
		)
	)
	(label "MUX_I2C_5_SDA"
		(at 82.55 86.36 0)
		(effects
			(font
				(size 1.27 1.27)
			)
			(justify left bottom)
		)
	)
	(label "VSYNC_CAM1_3V3"
		(at 381 214.63 180)
		(effects
			(font
				(size 1.27 1.27)
			)
			(justify right bottom)
		)
	)
	(label "SDA_CAM0"
		(at 30.48 162.56 0)
		(effects
			(font
				(size 1.27 1.27)
			)
			(justify left bottom)
		)
	)
	(label "CSI1_1_D0_P"
		(at 186.69 39.37 180)
		(effects
			(font
				(size 1.27 1.27)
			)
			(justify right bottom)
		)
	)
	(label "VSYNC_CAM0_3V3"
		(at 264.16 111.76 0)
		(effects
			(font
				(size 1.27 1.27)
			)
			(justify left bottom)
		)
	)
	(label "VSYNC_CAM3_3V3"
		(at 381 243.84 180)
		(effects
			(font
				(size 1.27 1.27)
			)
			(justify right bottom)
		)
	)
	(label "SCL_CAM2"
		(at 334.01 132.08 0)
		(effects
			(font
				(size 1.27 1.27)
			)
			(justify left bottom)
		)
	)
	(label "CSI3_0_D0_P"
		(at 186.69 119.38 180)
		(effects
			(font
				(size 1.27 1.27)
			)
			(justify right bottom)
		)
	)
	(label "CSI1_1_D1_P"
		(at 186.69 44.45 180)
		(effects
			(font
				(size 1.27 1.27)
			)
			(justify right bottom)
		)
	)
	(label "CSI1_0_D0_N"
		(at 266.7 38.1 0)
		(effects
			(font
				(size 1.27 1.27)
			)
			(justify left bottom)
		)
	)
	(label "CSI1_0_D1_P"
		(at 186.69 62.23 180)
		(effects
			(font
				(size 1.27 1.27)
			)
			(justify right bottom)
		)
	)
	(label "CSIA_5V"
		(at 224.79 154.94 0)
		(effects
			(font
				(size 1.27 1.27)
			)
			(justify left bottom)
		)
	)
	(label "MUX_I2C_4_SCL"
		(at 82.55 81.28 0)
		(effects
			(font
				(size 1.27 1.27)
			)
			(justify left bottom)
		)
	)
	(label "CSI3_1_D0_N"
		(at 186.69 93.98 180)
		(effects
			(font
				(size 1.27 1.27)
			)
			(justify right bottom)
		)
	)
	(label "I2C_MUX_SDA"
		(at 60.96 60.96 180)
		(effects
			(font
				(size 1.27 1.27)
			)
			(justify right bottom)
		)
	)
	(label "CSI3_1_D1_N"
		(at 344.17 88.9 0)
		(effects
			(font
				(size 1.27 1.27)
			)
			(justify left bottom)
		)
	)
	(label "SCL_CAM1"
		(at 256.54 137.16 0)
		(effects
			(font
				(size 1.27 1.27)
			)
			(justify left bottom)
		)
	)
	(label "SCL_CAM1"
		(at 30.48 153.67 0)
		(effects
			(font
				(size 1.27 1.27)
			)
			(justify left bottom)
		)
	)
	(label "CSI3_1_D1_P"
		(at 344.17 91.44 0)
		(effects
			(font
				(size 1.27 1.27)
			)
			(justify left bottom)
		)
	)
	(label "VSYNC_CAM2_3V3"
		(at 381 241.3 180)
		(effects
			(font
				(size 1.27 1.27)
			)
			(justify right bottom)
		)
	)
	(label "CSI3_0_D1_N"
		(at 266.7 78.74 0)
		(effects
			(font
				(size 1.27 1.27)
			)
			(justify left bottom)
		)
	)
	(label "SDA_CAM3"
		(at 67.31 156.21 0)
		(effects
			(font
				(size 1.27 1.27)
			)
			(justify left bottom)
		)
	)
	(label "CSI1_1_D0_N"
		(at 186.69 41.91 180)
		(effects
			(font
				(size 1.27 1.27)
			)
			(justify right bottom)
		)
	)
	(label "CSI3_1_D0_N"
		(at 344.17 93.98 0)
		(effects
			(font
				(size 1.27 1.27)
			)
			(justify left bottom)
		)
	)
	(label "CSIA_3V3"
		(at 224.79 149.86 0)
		(effects
			(font
				(size 1.27 1.27)
			)
			(justify left bottom)
		)
	)
	(label "CSI1_1_D0_N"
		(at 344.17 48.26 0)
		(effects
			(font
				(size 1.27 1.27)
			)
			(justify left bottom)
		)
	)
	(label "SCL_CAM2"
		(at 92.71 66.04 180)
		(effects
			(font
				(size 1.27 1.27)
			)
			(justify right bottom)
		)
	)
	(label "SCL_CAM3"
		(at 334.01 137.16 0)
		(effects
			(font
				(size 1.27 1.27)
			)
			(justify left bottom)
		)
	)
	(label "SCL_CAM3"
		(at 92.71 73.66 180)
		(effects
			(font
				(size 1.27 1.27)
			)
			(justify right bottom)
		)
	)
	(global_label "CSI3_D1_P"
		(shape output)
		(at 134.62 101.6 180)
		(fields_autoplaced yes)
		(effects
			(font
				(size 1.27 1.27)
			)
			(justify right)
		)
		(property "Intersheetrefs" "${INTERSHEET_REFS}"
			(at 122.2283 101.5206 0)
			(effects
				(font
					(size 1.27 1.27)
				)
				(justify right)
			)
		)
	)
	(global_label "CSI3_D0_P"
		(shape output)
		(at 134.62 96.52 180)
		(fields_autoplaced yes)
		(effects
			(font
				(size 1.27 1.27)
			)
			(justify right)
		)
		(property "Intersheetrefs" "${INTERSHEET_REFS}"
			(at 122.2283 96.4406 0)
			(effects
				(font
					(size 1.27 1.27)
				)
				(justify right)
			)
		)
	)
	(global_label "VSYNC_CAM0"
		(shape input)
		(at 340.36 212.09 180)
		(fields_autoplaced yes)
		(effects
			(font
				(size 1.27 1.27)
			)
			(justify right)
		)
		(property "Intersheetrefs" "${INTERSHEET_REFS}"
			(at 325.9726 212.0106 0)
			(effects
				(font
					(size 1.27 1.27)
				)
				(justify right)
			)
		)
	)
	(global_label "SCL_CAM"
		(shape input)
		(at 31.75 63.5 180)
		(effects
			(font
				(size 1.27 1.27)
			)
			(justify right)
		)
		(property "Intersheetrefs" "${INTERSHEET_REFS}"
			(at 19.05 63.5 0)
			(effects
				(font
					(size 1.27 1.27)
				)
				(justify right)
			)
		)
	)
	(global_label "VSYNC_CAM2"
		(shape input)
		(at 340.36 241.3 180)
		(fields_autoplaced yes)
		(effects
			(font
				(size 1.27 1.27)
			)
			(justify right)
		)
		(property "Intersheetrefs" "${INTERSHEET_REFS}"
			(at 325.9726 241.2206 0)
			(effects
				(font
					(size 1.27 1.27)
				)
				(justify right)
			)
		)
	)
	(global_label "CSI0_D0_N"
		(shape output)
		(at 281.94 48.26 180)
		(fields_autoplaced yes)
		(effects
			(font
				(size 1.27 1.27)
			)
			(justify right)
		)
		(property "Intersheetrefs" "${INTERSHEET_REFS}"
			(at 269.4879 48.1806 0)
			(effects
				(font
					(size 1.27 1.27)
				)
				(justify right)
			)
		)
	)
	(global_label "CSI2_D0_P"
		(shape output)
		(at 281.94 96.52 180)
		(fields_autoplaced yes)
		(effects
			(font
				(size 1.27 1.27)
			)
			(justify right)
		)
		(property "Intersheetrefs" "${INTERSHEET_REFS}"
			(at 269.5483 96.4406 0)
			(effects
				(font
					(size 1.27 1.27)
				)
				(justify right)
			)
		)
	)
	(global_label "CSI0_D0_P"
		(shape output)
		(at 281.94 50.8 180)
		(fields_autoplaced yes)
		(effects
			(font
				(size 1.27 1.27)
			)
			(justify right)
		)
		(property "Intersheetrefs" "${INTERSHEET_REFS}"
			(at 269.5483 50.7206 0)
			(effects
				(font
					(size 1.27 1.27)
				)
				(justify right)
			)
		)
	)
	(global_label "VSYNC_CAM3"
		(shape input)
		(at 340.36 243.84 180)
		(fields_autoplaced yes)
		(effects
			(font
				(size 1.27 1.27)
			)
			(justify right)
		)
		(property "Intersheetrefs" "${INTERSHEET_REFS}"
			(at 325.9726 243.7606 0)
			(effects
				(font
					(size 1.27 1.27)
				)
				(justify right)
			)
		)
	)
	(global_label "SDA_CAM"
		(shape bidirectional)
		(at 31.75 60.96 180)
		(effects
			(font
				(size 1.27 1.27)
			)
			(justify right)
		)
		(property "Intersheetrefs" "${INTERSHEET_REFS}"
			(at 19.05 60.96 0)
			(effects
				(font
					(size 1.27 1.27)
				)
				(justify right)
			)
		)
	)
	(global_label "CSI0_CLK_N"
		(shape input)
		(at 281.94 55.88 180)
		(fields_autoplaced yes)
		(effects
			(font
				(size 1.27 1.27)
			)
			(justify right)
		)
		(property "Intersheetrefs" "${INTERSHEET_REFS}"
			(at 268.3993 55.8006 0)
			(effects
				(font
					(size 1.27 1.27)
				)
				(justify right)
			)
		)
	)
	(global_label "CSI2_D1_N"
		(shape output)
		(at 281.94 88.9 180)
		(fields_autoplaced yes)
		(effects
			(font
				(size 1.27 1.27)
			)
			(justify right)
		)
		(property "Intersheetrefs" "${INTERSHEET_REFS}"
			(at 269.4879 88.8206 0)
			(effects
				(font
					(size 1.27 1.27)
				)
				(justify right)
			)
		)
	)
	(global_label "CSI1_D1_P"
		(shape output)
		(at 134.62 44.45 180)
		(fields_autoplaced yes)
		(effects
			(font
				(size 1.27 1.27)
			)
			(justify right)
		)
		(property "Intersheetrefs" "${INTERSHEET_REFS}"
			(at 122.2283 44.3706 0)
			(effects
				(font
					(size 1.27 1.27)
				)
				(justify right)
			)
		)
	)
	(global_label "CSI1_CLK_P"
		(shape input)
		(at 360.68 58.42 180)
		(fields_autoplaced yes)
		(effects
			(font
				(size 1.27 1.27)
			)
			(justify right)
		)
		(property "Intersheetrefs" "${INTERSHEET_REFS}"
			(at 347.1998 58.3406 0)
			(effects
				(font
					(size 1.27 1.27)
				)
				(justify right)
			)
		)
	)
	(global_label "CSIA_PEN"
		(shape input)
		(at 60.96 215.9 180)
		(fields_autoplaced yes)
		(effects
			(font
				(size 1.27 1.27)
			)
			(justify right)
		)
		(property "Intersheetrefs" "${INTERSHEET_REFS}"
			(at 49.6569 215.8206 0)
			(effects
				(font
					(size 1.27 1.27)
				)
				(justify right)
			)
		)
	)
	(global_label "CSI2_D0_N"
		(shape output)
		(at 281.94 93.98 180)
		(fields_autoplaced yes)
		(effects
			(font
				(size 1.27 1.27)
			)
			(justify right)
		)
		(property "Intersheetrefs" "${INTERSHEET_REFS}"
			(at 269.4879 93.9006 0)
			(effects
				(font
					(size 1.27 1.27)
				)
				(justify right)
			)
		)
	)
	(global_label "CSI2_CLK_N"
		(shape input)
		(at 281.94 101.6 180)
		(fields_autoplaced yes)
		(effects
			(font
				(size 1.27 1.27)
			)
			(justify right)
		)
		(property "Intersheetrefs" "${INTERSHEET_REFS}"
			(at 268.3993 101.5206 0)
			(effects
				(font
					(size 1.27 1.27)
				)
				(justify right)
			)
		)
	)
	(global_label "CSI1_CLK_N"
		(shape input)
		(at 360.68 55.88 180)
		(fields_autoplaced yes)
		(effects
			(font
				(size 1.27 1.27)
			)
			(justify right)
		)
		(property "Intersheetrefs" "${INTERSHEET_REFS}"
			(at 347.1393 55.8006 0)
			(effects
				(font
					(size 1.27 1.27)
				)
				(justify right)
			)
		)
	)
	(global_label "CSI0_D1_N"
		(shape output)
		(at 281.94 43.18 180)
		(fields_autoplaced yes)
		(effects
			(font
				(size 1.27 1.27)
			)
			(justify right)
		)
		(property "Intersheetrefs" "${INTERSHEET_REFS}"
			(at 269.4879 43.1006 0)
			(effects
				(font
					(size 1.27 1.27)
				)
				(justify right)
			)
		)
	)
	(global_label "CSI2_CLK_P"
		(shape input)
		(at 281.94 104.14 180)
		(fields_autoplaced yes)
		(effects
			(font
				(size 1.27 1.27)
			)
			(justify right)
		)
		(property "Intersheetrefs" "${INTERSHEET_REFS}"
			(at 268.4598 104.0606 0)
			(effects
				(font
					(size 1.27 1.27)
				)
				(justify right)
			)
		)
	)
	(global_label "VSYNC_CAM1"
		(shape input)
		(at 340.36 214.63 180)
		(fields_autoplaced yes)
		(effects
			(font
				(size 1.27 1.27)
			)
			(justify right)
		)
		(property "Intersheetrefs" "${INTERSHEET_REFS}"
			(at 325.9726 214.5506 0)
			(effects
				(font
					(size 1.27 1.27)
				)
				(justify right)
			)
		)
	)
	(global_label "CSIB_FLG"
		(shape output)
		(at 198.12 231.14 0)
		(fields_autoplaced yes)
		(effects
			(font
				(size 1.27 1.27)
			)
			(justify left)
		)
		(property "Intersheetrefs" "${INTERSHEET_REFS}"
			(at 209.2417 231.0606 0)
			(effects
				(font
					(size 1.27 1.27)
				)
				(justify left)
			)
		)
	)
	(global_label "CSI1_D0_P"
		(shape output)
		(at 134.62 39.37 180)
		(fields_autoplaced yes)
		(effects
			(font
				(size 1.27 1.27)
			)
			(justify right)
		)
		(property "Intersheetrefs" "${INTERSHEET_REFS}"
			(at 122.2283 39.2906 0)
			(effects
				(font
					(size 1.27 1.27)
				)
				(justify right)
			)
		)
	)
	(global_label "CSI1_D1_N"
		(shape output)
		(at 134.62 46.99 180)
		(fields_autoplaced yes)
		(effects
			(font
				(size 1.27 1.27)
			)
			(justify right)
		)
		(property "Intersheetrefs" "${INTERSHEET_REFS}"
			(at 122.1679 46.9106 0)
			(effects
				(font
					(size 1.27 1.27)
				)
				(justify right)
			)
		)
	)
	(global_label "CSIA_FLG"
		(shape output)
		(at 88.9 231.14 0)
		(fields_autoplaced yes)
		(effects
			(font
				(size 1.27 1.27)
			)
			(justify left)
		)
		(property "Intersheetrefs" "${INTERSHEET_REFS}"
			(at 99.8402 231.0606 0)
			(effects
				(font
					(size 1.27 1.27)
				)
				(justify left)
			)
		)
	)
	(global_label "CSI0_D1_P"
		(shape output)
		(at 281.94 45.72 180)
		(fields_autoplaced yes)
		(effects
			(font
				(size 1.27 1.27)
			)
			(justify right)
		)
		(property "Intersheetrefs" "${INTERSHEET_REFS}"
			(at 269.5483 45.6406 0)
			(effects
				(font
					(size 1.27 1.27)
				)
				(justify right)
			)
		)
	)
	(global_label "CSI2_D1_P"
		(shape output)
		(at 281.94 91.44 180)
		(fields_autoplaced yes)
		(effects
			(font
				(size 1.27 1.27)
			)
			(justify right)
		)
		(property "Intersheetrefs" "${INTERSHEET_REFS}"
			(at 269.5483 91.3606 0)
			(effects
				(font
					(size 1.27 1.27)
				)
				(justify right)
			)
		)
	)
	(global_label "CSIB_PEN"
		(shape input)
		(at 170.18 215.9 180)
		(fields_autoplaced yes)
		(effects
			(font
				(size 1.27 1.27)
			)
			(justify right)
		)
		(property "Intersheetrefs" "${INTERSHEET_REFS}"
			(at 158.6955 215.8206 0)
			(effects
				(font
					(size 1.27 1.27)
				)
				(justify right)
			)
		)
	)
	(global_label "CSI3_D1_N"
		(shape output)
		(at 134.62 99.06 180)
		(fields_autoplaced yes)
		(effects
			(font
				(size 1.27 1.27)
			)
			(justify right)
		)
		(property "Intersheetrefs" "${INTERSHEET_REFS}"
			(at 122.1679 98.9806 0)
			(effects
				(font
					(size 1.27 1.27)
				)
				(justify right)
			)
		)
	)
	(global_label "CSI3_CLK_N"
		(shape input)
		(at 360.68 101.6 180)
		(fields_autoplaced yes)
		(effects
			(font
				(size 1.27 1.27)
			)
			(justify right)
		)
		(property "Intersheetrefs" "${INTERSHEET_REFS}"
			(at 347.1393 101.5206 0)
			(effects
				(font
					(size 1.27 1.27)
				)
				(justify right)
			)
		)
	)
	(global_label "CSI3_CLK_P"
		(shape input)
		(at 360.68 104.14 180)
		(fields_autoplaced yes)
		(effects
			(font
				(size 1.27 1.27)
			)
			(justify right)
		)
		(property "Intersheetrefs" "${INTERSHEET_REFS}"
			(at 347.1998 104.0606 0)
			(effects
				(font
					(size 1.27 1.27)
				)
				(justify right)
			)
		)
	)
	(global_label "CSI1_D0_N"
		(shape output)
		(at 134.62 41.91 180)
		(fields_autoplaced yes)
		(effects
			(font
				(size 1.27 1.27)
			)
			(justify right)
		)
		(property "Intersheetrefs" "${INTERSHEET_REFS}"
			(at 122.1679 41.8306 0)
			(effects
				(font
					(size 1.27 1.27)
				)
				(justify right)
			)
		)
	)
	(global_label "CSI3_D0_N"
		(shape output)
		(at 134.62 93.98 180)
		(fields_autoplaced yes)
		(effects
			(font
				(size 1.27 1.27)
			)
			(justify right)
		)
		(property "Intersheetrefs" "${INTERSHEET_REFS}"
			(at 122.1679 93.9006 0)
			(effects
				(font
					(size 1.27 1.27)
				)
				(justify right)
			)
		)
	)
	(global_label "CSI0_CLK_P"
		(shape input)
		(at 281.94 58.42 180)
		(fields_autoplaced yes)
		(effects
			(font
				(size 1.27 1.27)
			)
			(justify right)
		)
		(property "Intersheetrefs" "${INTERSHEET_REFS}"
			(at 268.4598 58.3406 0)
			(effects
				(font
					(size 1.27 1.27)
				)
				(justify right)
			)
		)
	)
	(symbol
		(lib_id "antmicropower:+1V8")
		(at 334.01 226.06 0)
		(unit 1)
		(exclude_from_sim no)
		(in_bom yes)
		(on_board yes)
		(dnp no)
		(property "Reference" "#PWR0171"
			(at 334.01 229.87 0)
			(effects
				(font
					(size 1.27 1.27)
				)
				(justify left bottom)
				(hide yes)
			)
		)
		(property "Value" "+1V8"
			(at 330.835 222.25 0)
			(effects
				(font
					(size 1.27 1.27)
					(thickness 0.15)
				)
				(justify left)
			)
		)
		(property "Footprint" ""
			(at 349.25 233.68 0)
			(effects
				(font
					(size 1.27 1.27)
					(thickness 0.15)
				)
				(justify left bottom)
				(hide yes)
			)
		)
		(property "Datasheet" ""
			(at 349.25 236.22 0)
			(effects
				(font
					(size 1.27 1.27)
					(thickness 0.15)
				)
				(justify left bottom)
				(hide yes)
			)
		)
		(property "Description" ""
			(at 334.01 226.06 0)
			(effects
				(font
					(size 1.27 1.27)
				)
				(hide yes)
			)
		)
		(property "Author" "Antmicro"
			(at 349.25 231.14 0)
			(effects
				(font
					(size 1.27 1.27)
					(thickness 0.15)
				)
				(justify left bottom)
				(hide yes)
			)
		)
		(property "License" "Apache-2.0"
			(at 349.25 233.68 0)
			(effects
				(font
					(size 1.27 1.27)
					(thickness 0.15)
				)
				(justify left bottom)
				(hide yes)
			)
		)
		(pin "1"
		)
		(instances
			(project "jetson-orin-baseboard"
				(path ""
					(reference "#PWR0171")
					(unit 1)
				)
			)
		)
	)
	(symbol
		(lib_id "antmicroResistors0402:R_4k7_0402")
		(at 232.41 252.73 90)
		(unit 1)
		(exclude_from_sim no)
		(in_bom yes)
		(on_board yes)
		(dnp no)
		(property "Reference" "R10"
			(at 233.68 248.92 90)
			(effects
				(font
					(size 1.27 1.27)
				)
				(justify right)
			)
		)
		(property "Value" "R_4k7_0402"
			(at 245.11 232.41 0)
			(effects
				(font
					(size 1.27 1.27)
					(thickness 0.15)
				)
				(justify left bottom)
				(hide yes)
			)
		)
		(property "Footprint" "antmicro-footprints:R_0402_1005Metric"
			(at 247.65 232.41 0)
			(effects
				(font
					(size 1.27 1.27)
					(thickness 0.15)
				)
				(justify left bottom)
				(hide yes)
			)
		)
		(property "Datasheet" "https://www.bourns.com/docs/product-datasheets/cr.pdf"
			(at 250.19 232.41 0)
			(effects
				(font
					(size 1.27 1.27)
					(thickness 0.15)
				)
				(justify left bottom)
				(hide yes)
			)
		)
		(property "Description" ""
			(at 232.41 252.73 0)
			(effects
				(font
					(size 1.27 1.27)
				)
				(hide yes)
			)
		)
		(property "Manufacturer" "Bourns"
			(at 255.27 232.41 0)
			(effects
				(font
					(size 1.27 1.27)
					(thickness 0.15)
				)
				(justify left bottom)
				(hide yes)
			)
		)
		(property "MPN" "CR0402-FX-4701GLF"
			(at 252.73 232.41 0)
			(effects
				(font
					(size 1.27 1.27)
					(thickness 0.15)
				)
				(justify left bottom)
				(hide yes)
			)
		)
		(property "Val" "4k7"
			(at 233.68 251.46 90)
			(effects
				(font
					(size 1.27 1.27)
					(thickness 0.15)
				)
				(justify right)
			)
		)
		(property "License" "Apache-2.0"
			(at 257.81 232.41 0)
			(effects
				(font
					(size 1.27 1.27)
					(thickness 0.15)
				)
				(justify left bottom)
				(hide yes)
			)
		)
		(property "Author" "Antmicro"
			(at 260.35 232.41 0)
			(effects
				(font
					(size 1.27 1.27)
					(thickness 0.15)
				)
				(justify left bottom)
				(hide yes)
			)
		)
		(property "Tolerance" "1%"
			(at 242.57 232.41 0)
			(effects
				(font
					(size 1.27 1.27)
				)
				(justify left bottom)
				(hide yes)
			)
		)
		(pin "1"
		)
		(pin "2"
		)
		(instances
			(project "jetson-orin-baseboard"
				(path ""
					(reference "R10")
					(unit 1)
				)
			)
		)
	)
	(symbol
		(lib_id "antmicropower:GND")
		(at 334.01 234.95 0)
		(unit 1)
		(exclude_from_sim no)
		(in_bom yes)
		(on_board yes)
		(dnp no)
		(property "Reference" "#PWR0181"
			(at 334.01 241.3 0)
			(effects
				(font
					(size 1.27 1.27)
				)
				(justify left bottom)
				(hide yes)
			)
		)
		(property "Value" "GND"
			(at 334.01 238.76 0)
			(effects
				(font
					(size 1.27 1.27)
					(thickness 0.15)
				)
			)
		)
		(property "Footprint" ""
			(at 342.9 242.57 0)
			(effects
				(font
					(size 1.27 1.27)
					(thickness 0.15)
				)
				(justify left bottom)
				(hide yes)
			)
		)
		(property "Datasheet" ""
			(at 342.9 247.65 0)
			(effects
				(font
					(size 1.27 1.27)
					(thickness 0.15)
				)
				(justify left bottom)
				(hide yes)
			)
		)
		(property "Description" ""
			(at 334.01 234.95 0)
			(effects
				(font
					(size 1.27 1.27)
				)
				(hide yes)
			)
		)
		(property "Author" "Antmicro"
			(at 342.9 242.57 0)
			(effects
				(font
					(size 1.27 1.27)
					(thickness 0.15)
				)
				(justify left bottom)
				(hide yes)
			)
		)
		(property "License" "Apache-2.0"
			(at 342.9 245.11 0)
			(effects
				(font
					(size 1.27 1.27)
					(thickness 0.15)
				)
				(justify left bottom)
				(hide yes)
			)
		)
		(pin "1"
		)
		(instances
			(project "jetson-orin-baseboard"
				(path ""
					(reference "#PWR0181")
					(unit 1)
				)
			)
		)
	)
	(symbol
		(lib_id "antmicroLogicSignalSwitchesMultiplexersDecoders:PI4MSD5V9548AZDEX")
		(at 62.23 48.26 0)
		(unit 1)
		(exclude_from_sim no)
		(in_bom yes)
		(on_board yes)
		(dnp no)
		(property "Reference" "U26"
			(at 72.39 41.91 0)
			(effects
				(font
					(size 1.27 1.27)
				)
			)
		)
		(property "Value" "PI4MSD5V9548AZDEX"
			(at 97.79 53.34 0)
			(effects
				(font
					(size 1.27 1.27)
					(thickness 0.15)
				)
				(justify left bottom)
				(hide yes)
			)
		)
		(property "Footprint" "antmicro-footprints:VQFN-24-1EP_3.8x3.8x1.0mm_P0.5mm"
			(at 97.79 55.88 0)
			(effects
				(font
					(size 1.27 1.27)
					(thickness 0.15)
				)
				(justify left bottom)
				(hide yes)
			)
		)
		(property "Datasheet" "https://www.mouser.com/datasheet/2/115/DIOD_S_A0003139195_1-2542233.pdf"
			(at 97.79 58.42 0)
			(effects
				(font
					(size 1.27 1.27)
					(thickness 0.15)
				)
				(justify left bottom)
				(hide yes)
			)
		)
		(property "Description" ""
			(at 62.23 48.26 0)
			(effects
				(font
					(size 1.27 1.27)
				)
				(hide yes)
			)
		)
		(property "Manufacturer" "Diodes Incorporated"
			(at 97.79 60.96 0)
			(effects
				(font
					(size 1.27 1.27)
					(thickness 0.15)
				)
				(justify left bottom)
				(hide yes)
			)
		)
		(property "MPN" "PI4MSD5V9548AZDEX"
			(at 72.39 44.45 0)
			(effects
				(font
					(size 1.27 1.27)
					(thickness 0.15)
				)
			)
		)
		(property "Author" "Antmicro"
			(at 97.79 66.04 0)
			(effects
				(font
					(size 1.27 1.27)
					(thickness 0.15)
				)
				(justify left bottom)
				(hide yes)
			)
		)
		(property "License" "Apache-2.0"
			(at 97.79 68.58 0)
			(effects
				(font
					(size 1.27 1.27)
					(thickness 0.15)
				)
				(justify left bottom)
				(hide yes)
			)
		)
		(pin "1"
		)
		(pin "10"
		)
		(pin "11"
		)
		(pin "12"
		)
		(pin "13"
		)
		(pin "14"
		)
		(pin "15"
		)
		(pin "16"
		)
		(pin "17"
		)
		(pin "18"
		)
		(pin "19"
		)
		(pin "2"
		)
		(pin "20"
		)
		(pin "21"
		)
		(pin "22"
		)
		(pin "23"
		)
		(pin "24"
		)
		(pin "25"
		)
		(pin "3"
		)
		(pin "4"
		)
		(pin "5"
		)
		(pin "6"
		)
		(pin "7"
		)
		(pin "8"
		)
		(pin "9"
		)
		(instances
			(project "jetson-orin-baseboard"
				(path ""
					(reference "U26")
					(unit 1)
				)
			)
		)
	)
	(symbol
		(lib_id "antmicropower:GND")
		(at 76.2 241.3 0)
		(unit 1)
		(exclude_from_sim no)
		(in_bom yes)
		(on_board yes)
		(dnp no)
		(property "Reference" "#PWR0161"
			(at 76.2 247.65 0)
			(effects
				(font
					(size 1.27 1.27)
				)
				(justify left bottom)
				(hide yes)
			)
		)
		(property "Value" "GND"
			(at 76.2 245.11 0)
			(effects
				(font
					(size 1.27 1.27)
					(thickness 0.15)
				)
			)
		)
		(property "Footprint" ""
			(at 85.09 248.92 0)
			(effects
				(font
					(size 1.27 1.27)
					(thickness 0.15)
				)
				(justify left bottom)
				(hide yes)
			)
		)
		(property "Datasheet" ""
			(at 85.09 254 0)
			(effects
				(font
					(size 1.27 1.27)
					(thickness 0.15)
				)
				(justify left bottom)
				(hide yes)
			)
		)
		(property "Description" ""
			(at 76.2 241.3 0)
			(effects
				(font
					(size 1.27 1.27)
				)
				(hide yes)
			)
		)
		(property "Author" "Antmicro"
			(at 85.09 248.92 0)
			(effects
				(font
					(size 1.27 1.27)
					(thickness 0.15)
				)
				(justify left bottom)
				(hide yes)
			)
		)
		(property "License" "Apache-2.0"
			(at 85.09 251.46 0)
			(effects
				(font
					(size 1.27 1.27)
					(thickness 0.15)
				)
				(justify left bottom)
				(hide yes)
			)
		)
		(pin "1"
		)
		(instances
			(project "jetson-orin-baseboard"
				(path ""
					(reference "#PWR0161")
					(unit 1)
				)
			)
		)
	)
	(symbol
		(lib_id "antmicroResistorNetworksArrays:R_4x0R_0201_array")
		(at 157.48 121.92 0)
		(mirror x)
		(unit 1)
		(exclude_from_sim no)
		(in_bom yes)
		(on_board yes)
		(dnp no)
		(property "Reference" "R108"
			(at 162.56 108.585 0)
			(effects
				(font
					(size 1.27 1.27)
				)
			)
		)
		(property "Value" "R_4x0R_0201_array"
			(at 184.15 114.3 0)
			(effects
				(font
					(size 1.27 1.27)
					(thickness 0.15)
				)
				(justify left bottom)
				(hide yes)
			)
		)
		(property "Footprint" "antmicro-footprints:R_Array_4x0201_Panasonic_EXB18V"
			(at 184.15 109.22 0)
			(effects
				(font
					(size 1.27 1.27)
					(thickness 0.15)
				)
				(justify left bottom)
				(hide yes)
			)
		)
		(property "Datasheet" "http://industrial.panasonic.com/cdbs/www-data/pdf/AOC0000/AOC0000C14.pdf"
			(at 184.15 106.68 0)
			(effects
				(font
					(size 1.27 1.27)
					(thickness 0.15)
				)
				(justify left bottom)
				(hide yes)
			)
		)
		(property "Description" ""
			(at 157.48 121.92 0)
			(effects
				(font
					(size 1.27 1.27)
				)
				(hide yes)
			)
		)
		(property "MPN" "EXB-18VR000X"
			(at 184.15 104.14 0)
			(effects
				(font
					(size 1.27 1.27)
					(thickness 0.15)
				)
				(justify left bottom)
				(hide yes)
			)
		)
		(property "Manufacturer" "Panasonic"
			(at 184.15 101.6 0)
			(effects
				(font
					(size 1.27 1.27)
					(thickness 0.15)
				)
				(justify left bottom)
				(hide yes)
			)
		)
		(property "Val" "4x0R_0201"
			(at 162.56 111.125 0)
			(effects
				(font
					(size 1.27 1.27)
					(thickness 0.15)
				)
			)
		)
		(property "Author" "Antmicro"
			(at 184.15 99.06 0)
			(effects
				(font
					(size 1.27 1.27)
					(thickness 0.15)
				)
				(justify left bottom)
				(hide yes)
			)
		)
		(property "License" "Apache-2.0"
			(at 184.15 96.52 0)
			(effects
				(font
					(size 1.27 1.27)
					(thickness 0.15)
				)
				(justify left bottom)
				(hide yes)
			)
		)
		(pin "1"
		)
		(pin "2"
		)
		(pin "3"
		)
		(pin "4"
		)
		(pin "5"
		)
		(pin "6"
		)
		(pin "7"
		)
		(pin "8"
		)
		(instances
			(project "jetson-orin-baseboard"
				(path ""
					(reference "R108")
					(unit 1)
				)
			)
		)
	)
	(symbol
		(lib_id "antmicroResistors0402:R_4k7_0402")
		(at 123.19 252.73 90)
		(unit 1)
		(exclude_from_sim no)
		(in_bom yes)
		(on_board yes)
		(dnp no)
		(property "Reference" "R8"
			(at 124.46 248.92 90)
			(effects
				(font
					(size 1.27 1.27)
				)
				(justify right)
			)
		)
		(property "Value" "R_4k7_0402"
			(at 135.89 232.41 0)
			(effects
				(font
					(size 1.27 1.27)
					(thickness 0.15)
				)
				(justify left bottom)
				(hide yes)
			)
		)
		(property "Footprint" "antmicro-footprints:R_0402_1005Metric"
			(at 138.43 232.41 0)
			(effects
				(font
					(size 1.27 1.27)
					(thickness 0.15)
				)
				(justify left bottom)
				(hide yes)
			)
		)
		(property "Datasheet" "https://www.bourns.com/docs/product-datasheets/cr.pdf"
			(at 140.97 232.41 0)
			(effects
				(font
					(size 1.27 1.27)
					(thickness 0.15)
				)
				(justify left bottom)
				(hide yes)
			)
		)
		(property "Description" ""
			(at 123.19 252.73 0)
			(effects
				(font
					(size 1.27 1.27)
				)
				(hide yes)
			)
		)
		(property "Manufacturer" "Bourns"
			(at 146.05 232.41 0)
			(effects
				(font
					(size 1.27 1.27)
					(thickness 0.15)
				)
				(justify left bottom)
				(hide yes)
			)
		)
		(property "MPN" "CR0402-FX-4701GLF"
			(at 143.51 232.41 0)
			(effects
				(font
					(size 1.27 1.27)
					(thickness 0.15)
				)
				(justify left bottom)
				(hide yes)
			)
		)
		(property "Val" "4k7"
			(at 124.46 251.46 90)
			(effects
				(font
					(size 1.27 1.27)
					(thickness 0.15)
				)
				(justify right)
			)
		)
		(property "License" "Apache-2.0"
			(at 148.59 232.41 0)
			(effects
				(font
					(size 1.27 1.27)
					(thickness 0.15)
				)
				(justify left bottom)
				(hide yes)
			)
		)
		(property "Author" "Antmicro"
			(at 151.13 232.41 0)
			(effects
				(font
					(size 1.27 1.27)
					(thickness 0.15)
				)
				(justify left bottom)
				(hide yes)
			)
		)
		(property "Tolerance" "1%"
			(at 133.35 232.41 0)
			(effects
				(font
					(size 1.27 1.27)
				)
				(justify left bottom)
				(hide yes)
			)
		)
		(pin "1"
		)
		(pin "2"
		)
		(instances
			(project "jetson-orin-baseboard"
				(path ""
					(reference "R8")
					(unit 1)
				)
			)
		)
	)
	(symbol
		(lib_id "antmicroResistors0402:R_0R_0402")
		(at 35.56 135.89 90)
		(unit 1)
		(exclude_from_sim no)
		(in_bom no)
		(on_board yes)
		(dnp yes)
		(property "Reference" "R171"
			(at 36.83 132.08 90)
			(effects
				(font
					(size 1.27 1.27)
				)
				(justify right)
			)
		)
		(property "Value" "R_0R_0402"
			(at 48.26 115.57 0)
			(effects
				(font
					(size 1.27 1.27)
					(thickness 0.15)
				)
				(justify left bottom)
				(hide yes)
			)
		)
		(property "Footprint" "antmicro-footprints:R_0402_1005Metric"
			(at 50.8 115.57 0)
			(effects
				(font
					(size 1.27 1.27)
					(thickness 0.15)
				)
				(justify left bottom)
				(hide yes)
			)
		)
		(property "Datasheet" "https://industrial.panasonic.com/cdbs/www-data/pdf/RDA0000/AOA0000C301.pdf"
			(at 53.34 115.57 0)
			(effects
				(font
					(size 1.27 1.27)
					(thickness 0.15)
				)
				(justify left bottom)
				(hide yes)
			)
		)
		(property "Description" ""
			(at 35.56 135.89 0)
			(effects
				(font
					(size 1.27 1.27)
				)
				(hide yes)
			)
		)
		(property "Manufacturer" "Panasonic"
			(at 58.42 115.57 0)
			(effects
				(font
					(size 1.27 1.27)
					(thickness 0.15)
				)
				(justify left bottom)
				(hide yes)
			)
		)
		(property "MPN" "ERJ2GE0R00X"
			(at 55.88 115.57 0)
			(effects
				(font
					(size 1.27 1.27)
					(thickness 0.15)
				)
				(justify left bottom)
				(hide yes)
			)
		)
		(property "Val" "0R"
			(at 36.83 134.62 90)
			(effects
				(font
					(size 1.27 1.27)
					(thickness 0.15)
				)
				(justify right)
			)
		)
		(property "License" "Apache-2.0"
			(at 60.96 115.57 0)
			(effects
				(font
					(size 1.27 1.27)
					(thickness 0.15)
				)
				(justify left bottom)
				(hide yes)
			)
		)
		(property "Author" "Antmicro"
			(at 63.5 115.57 0)
			(effects
				(font
					(size 1.27 1.27)
					(thickness 0.15)
				)
				(justify left bottom)
				(hide yes)
			)
		)
		(property "Tolerance" "~"
			(at 45.72 115.57 0)
			(effects
				(font
					(size 1.27 1.27)
				)
				(justify left bottom)
				(hide yes)
			)
		)
		(property "Current" "1A"
			(at 66.04 115.57 0)
			(effects
				(font
					(size 1.27 1.27)
					(thickness 0.15)
				)
				(justify left bottom)
				(hide yes)
			)
		)
		(pin "1"
		)
		(pin "2"
		)
		(instances
			(project "jetson-orin-baseboard"
				(path ""
					(reference "R171")
					(unit 1)
				)
			)
		)
	)
	(symbol
		(lib_id "antmicroTestPoints:TP_0.75mm_SMD")
		(at 97.79 93.98 0)
		(unit 1)
		(exclude_from_sim no)
		(in_bom no)
		(on_board yes)
		(dnp no)
		(property "Reference" "TP40"
			(at 101.6 93.9799 0)
			(effects
				(font
					(size 1.27 1.27)
				)
				(justify left)
			)
		)
		(property "Value" "TP_0.75mm_SMD"
			(at 107.95 97.79 0)
			(effects
				(font
					(size 1.27 1.27)
					(thickness 0.15)
				)
				(justify left bottom)
				(hide yes)
			)
		)
		(property "Footprint" "antmicro-footprints:TP_SMD_0.75mm"
			(at 107.95 100.33 0)
			(effects
				(font
					(size 1.27 1.27)
					(thickness 0.15)
				)
				(justify left bottom)
				(hide yes)
			)
		)
		(property "Datasheet" ""
			(at 115.57 106.68 0)
			(effects
				(font
					(size 1.27 1.27)
					(thickness 0.15)
				)
				(justify left bottom)
				(hide yes)
			)
		)
		(property "Description" ""
			(at 97.79 93.98 0)
			(effects
				(font
					(size 1.27 1.27)
				)
				(hide yes)
			)
		)
		(property "MPN" ""
			(at 108.585 105.41 0)
			(effects
				(font
					(size 1.27 1.27)
					(thickness 0.15)
				)
				(justify left bottom)
				(hide yes)
			)
		)
		(property "Manufacturer" ""
			(at 108.585 100.33 0)
			(effects
				(font
					(size 1.27 1.27)
					(thickness 0.15)
				)
				(justify left bottom)
				(hide yes)
			)
		)
		(property "Author" "Antmicro"
			(at 107.95 102.87 0)
			(effects
				(font
					(size 1.27 1.27)
					(thickness 0.15)
				)
				(justify left bottom)
				(hide yes)
			)
		)
		(property "License" "Apache-2.0"
			(at 107.95 105.41 0)
			(effects
				(font
					(size 1.27 1.27)
					(thickness 0.15)
				)
				(justify left bottom)
				(hide yes)
			)
		)
		(pin "1"
		)
		(instances
			(project "jetson-orin-baseboard"
				(path ""
					(reference "TP40")
					(unit 1)
				)
			)
		)
	)
	(symbol
		(lib_id "antmicroFCCConnectors:Conn_FFC_WE_68715014522")
		(at 364.49 33.02 0)
		(unit 1)
		(exclude_from_sim no)
		(in_bom yes)
		(on_board yes)
		(dnp no)
		(fields_autoplaced yes)
		(property "Reference" "J8"
			(at 373.38 97.155 0)
			(effects
				(font
					(size 1.27 1.27)
				)
				(justify left)
			)
		)
		(property "Value" "Conn_FFC_WE_68715014522"
			(at 383.54 40.64 0)
			(effects
				(font
					(size 1.27 1.27)
					(thickness 0.15)
				)
				(justify left bottom)
				(hide yes)
			)
		)
		(property "Footprint" "antmicro-footprints:Conn_FFC_WE_68715014x22"
			(at 383.54 43.18 0)
			(effects
				(font
					(size 1.27 1.27)
					(thickness 0.15)
				)
				(justify left bottom)
				(hide yes)
			)
		)
		(property "Datasheet" "https://www.we-online.com/components/products/datasheet/68715014522.pdf"
			(at 383.54 45.72 0)
			(effects
				(font
					(size 1.27 1.27)
					(thickness 0.15)
				)
				(justify left bottom)
				(hide yes)
			)
		)
		(property "Description" ""
			(at 364.49 33.02 0)
			(effects
				(font
					(size 1.27 1.27)
				)
				(hide yes)
			)
		)
		(property "MPN" "68715014522"
			(at 373.38 99.695 0)
			(effects
				(font
					(size 1.27 1.27)
					(thickness 0.15)
				)
				(justify left)
			)
		)
		(property "Manufacturer" "Würth Elektronik"
			(at 383.54 50.8 0)
			(effects
				(font
					(size 1.27 1.27)
					(thickness 0.15)
				)
				(justify left bottom)
				(hide yes)
			)
		)
		(property "Author" "Antmicro"
			(at 383.54 53.34 0)
			(effects
				(font
					(size 1.27 1.27)
					(thickness 0.15)
				)
				(justify left bottom)
				(hide yes)
			)
		)
		(property "License" "Apache-2.0"
			(at 383.54 55.88 0)
			(effects
				(font
					(size 1.27 1.27)
					(thickness 0.15)
				)
				(justify left bottom)
				(hide yes)
			)
		)
		(pin "1"
		)
		(pin "10"
		)
		(pin "11"
		)
		(pin "12"
		)
		(pin "13"
		)
		(pin "14"
		)
		(pin "15"
		)
		(pin "16"
		)
		(pin "17"
		)
		(pin "18"
		)
		(pin "19"
		)
		(pin "2"
		)
		(pin "20"
		)
		(pin "21"
		)
		(pin "22"
		)
		(pin "23"
		)
		(pin "24"
		)
		(pin "25"
		)
		(pin "26"
		)
		(pin "27"
		)
		(pin "28"
		)
		(pin "29"
		)
		(pin "3"
		)
		(pin "30"
		)
		(pin "31"
		)
		(pin "32"
		)
		(pin "33"
		)
		(pin "34"
		)
		(pin "35"
		)
		(pin "36"
		)
		(pin "37"
		)
		(pin "38"
		)
		(pin "39"
		)
		(pin "4"
		)
		(pin "40"
		)
		(pin "41"
		)
		(pin "42"
		)
		(pin "43"
		)
		(pin "44"
		)
		(pin "45"
		)
		(pin "46"
		)
		(pin "47"
		)
		(pin "48"
		)
		(pin "49"
		)
		(pin "5"
		)
		(pin "50"
		)
		(pin "6"
		)
		(pin "7"
		)
		(pin "8"
		)
		(pin "9"
		)
		(pin "MP2"
		)
		(pin "MP1"
		)
		(instances
			(project "jetson-orin-baseboard"
				(path ""
					(reference "J8")
					(unit 1)
				)
			)
		)
	)
	(symbol
		(lib_id "antmicroLEDIndicationDiscrete:LED_G_0603_LTST-C190GKT")
		(at 251.46 167.64 90)
		(unit 1)
		(exclude_from_sim no)
		(in_bom yes)
		(on_board yes)
		(dnp no)
		(fields_autoplaced yes)
		(property "Reference" "D20"
			(at 254 163.83 90)
			(effects
				(font
					(size 1.27 1.27)
				)
				(justify right)
			)
		)
		(property "Value" "LED_G_0603_LTST-C190GKT"
			(at 259.08 144.78 0)
			(effects
				(font
					(size 1.27 1.27)
					(thickness 0.15)
				)
				(justify left bottom)
				(hide yes)
			)
		)
		(property "Footprint" "antmicro-footprints:LED_0603_1608Metric_G"
			(at 261.62 144.78 0)
			(effects
				(font
					(size 1.27 1.27)
					(thickness 0.15)
				)
				(justify left bottom)
				(hide yes)
			)
		)
		(property "Datasheet" "https://media.digikey.com/pdf/Data%20Sheets/Lite-On%20PDFs/LTST-C190GKT.pdf"
			(at 264.16 144.78 0)
			(effects
				(font
					(size 1.27 1.27)
					(thickness 0.15)
				)
				(justify left bottom)
				(hide yes)
			)
		)
		(property "Description" ""
			(at 251.46 167.64 0)
			(effects
				(font
					(size 1.27 1.27)
				)
				(hide yes)
			)
		)
		(property "MPN" "LTST-C190GKT"
			(at 266.7 144.78 0)
			(effects
				(font
					(size 1.27 1.27)
					(thickness 0.15)
				)
				(justify left bottom)
				(hide yes)
			)
		)
		(property "Manufacturer" "Lite-On"
			(at 269.24 144.78 0)
			(effects
				(font
					(size 1.27 1.27)
					(thickness 0.15)
				)
				(justify left bottom)
				(hide yes)
			)
		)
		(property "Author" "Antmicro"
			(at 271.78 144.78 0)
			(effects
				(font
					(size 1.27 1.27)
					(thickness 0.15)
				)
				(justify left bottom)
				(hide yes)
			)
		)
		(property "License" "Apache-2.0"
			(at 274.32 144.78 0)
			(effects
				(font
					(size 1.27 1.27)
					(thickness 0.15)
				)
				(justify left bottom)
				(hide yes)
			)
		)
		(property "Color" "Green"
			(at 254 166.37 90)
			(effects
				(font
					(size 1.27 1.27)
				)
				(justify right)
			)
		)
		(pin "1"
		)
		(pin "2"
		)
		(instances
			(project "jetson-orin-baseboard"
				(path ""
					(reference "D20")
					(unit 1)
				)
			)
		)
	)
	(symbol
		(lib_id "antmicroTestPoints:TP_0.75mm_SMD")
		(at 97.79 78.74 0)
		(unit 1)
		(exclude_from_sim no)
		(in_bom no)
		(on_board yes)
		(dnp no)
		(property "Reference" "TP36"
			(at 101.6 78.7399 0)
			(effects
				(font
					(size 1.27 1.27)
				)
				(justify left)
			)
		)
		(property "Value" "TP_0.75mm_SMD"
			(at 107.95 82.55 0)
			(effects
				(font
					(size 1.27 1.27)
					(thickness 0.15)
				)
				(justify left bottom)
				(hide yes)
			)
		)
		(property "Footprint" "antmicro-footprints:TP_SMD_0.75mm"
			(at 107.95 85.09 0)
			(effects
				(font
					(size 1.27 1.27)
					(thickness 0.15)
				)
				(justify left bottom)
				(hide yes)
			)
		)
		(property "Datasheet" ""
			(at 115.57 91.44 0)
			(effects
				(font
					(size 1.27 1.27)
					(thickness 0.15)
				)
				(justify left bottom)
				(hide yes)
			)
		)
		(property "Description" ""
			(at 97.79 78.74 0)
			(effects
				(font
					(size 1.27 1.27)
				)
				(hide yes)
			)
		)
		(property "MPN" ""
			(at 108.585 90.17 0)
			(effects
				(font
					(size 1.27 1.27)
					(thickness 0.15)
				)
				(justify left bottom)
				(hide yes)
			)
		)
		(property "Manufacturer" ""
			(at 108.585 85.09 0)
			(effects
				(font
					(size 1.27 1.27)
					(thickness 0.15)
				)
				(justify left bottom)
				(hide yes)
			)
		)
		(property "Author" "Antmicro"
			(at 107.95 87.63 0)
			(effects
				(font
					(size 1.27 1.27)
					(thickness 0.15)
				)
				(justify left bottom)
				(hide yes)
			)
		)
		(property "License" "Apache-2.0"
			(at 107.95 90.17 0)
			(effects
				(font
					(size 1.27 1.27)
					(thickness 0.15)
				)
				(justify left bottom)
				(hide yes)
			)
		)
		(pin "1"
		)
		(instances
			(project "jetson-orin-baseboard"
				(path ""
					(reference "TP36")
					(unit 1)
				)
			)
		)
	)
	(symbol
		(lib_id "antmicroResistors0402:R_0R_0402")
		(at 64.77 135.89 90)
		(unit 1)
		(exclude_from_sim no)
		(in_bom yes)
		(on_board yes)
		(dnp no)
		(property "Reference" "R174"
			(at 63.5 132.08 90)
			(effects
				(font
					(size 1.27 1.27)
				)
				(justify left)
			)
		)
		(property "Value" "R_0R_0402"
			(at 77.47 115.57 0)
			(effects
				(font
					(size 1.27 1.27)
					(thickness 0.15)
				)
				(justify left bottom)
				(hide yes)
			)
		)
		(property "Footprint" "antmicro-footprints:R_0402_1005Metric"
			(at 80.01 115.57 0)
			(effects
				(font
					(size 1.27 1.27)
					(thickness 0.15)
				)
				(justify left bottom)
				(hide yes)
			)
		)
		(property "Datasheet" "https://industrial.panasonic.com/cdbs/www-data/pdf/RDA0000/AOA0000C301.pdf"
			(at 82.55 115.57 0)
			(effects
				(font
					(size 1.27 1.27)
					(thickness 0.15)
				)
				(justify left bottom)
				(hide yes)
			)
		)
		(property "Description" ""
			(at 64.77 135.89 0)
			(effects
				(font
					(size 1.27 1.27)
				)
				(hide yes)
			)
		)
		(property "Manufacturer" "Panasonic"
			(at 87.63 115.57 0)
			(effects
				(font
					(size 1.27 1.27)
					(thickness 0.15)
				)
				(justify left bottom)
				(hide yes)
			)
		)
		(property "MPN" "ERJ2GE0R00X"
			(at 85.09 115.57 0)
			(effects
				(font
					(size 1.27 1.27)
					(thickness 0.15)
				)
				(justify left bottom)
				(hide yes)
			)
		)
		(property "Val" "0R"
			(at 63.5 134.62 90)
			(effects
				(font
					(size 1.27 1.27)
					(thickness 0.15)
				)
				(justify left)
			)
		)
		(property "License" "Apache-2.0"
			(at 90.17 115.57 0)
			(effects
				(font
					(size 1.27 1.27)
					(thickness 0.15)
				)
				(justify left bottom)
				(hide yes)
			)
		)
		(property "Author" "Antmicro"
			(at 92.71 115.57 0)
			(effects
				(font
					(size 1.27 1.27)
					(thickness 0.15)
				)
				(justify left bottom)
				(hide yes)
			)
		)
		(property "Tolerance" "~"
			(at 74.93 115.57 0)
			(effects
				(font
					(size 1.27 1.27)
				)
				(justify left bottom)
				(hide yes)
			)
		)
		(property "Current" "1A"
			(at 95.25 115.57 0)
			(effects
				(font
					(size 1.27 1.27)
					(thickness 0.15)
				)
				(justify left bottom)
				(hide yes)
			)
		)
		(pin "1"
		)
		(pin "2"
		)
		(instances
			(project "jetson-orin-baseboard"
				(path ""
					(reference "R174")
					(unit 1)
				)
			)
		)
	)
	(symbol
		(lib_id "antmicroCapacitors0402:C_100n_0402")
		(at 49.53 50.8 90)
		(unit 1)
		(exclude_from_sim no)
		(in_bom yes)
		(on_board yes)
		(dnp no)
		(fields_autoplaced yes)
		(property "Reference" "C89"
			(at 52.07 46.9836 90)
			(effects
				(font
					(size 1.27 1.27)
				)
				(justify right)
			)
		)
		(property "Value" "C_100n_0402"
			(at 59.69 30.48 0)
			(effects
				(font
					(size 1.27 1.27)
					(thickness 0.15)
				)
				(justify left bottom)
				(hide yes)
			)
		)
		(property "Footprint" "antmicro-footprints:C_0402_1005Metric"
			(at 62.23 30.48 0)
			(effects
				(font
					(size 1.27 1.27)
					(thickness 0.15)
				)
				(justify left bottom)
				(hide yes)
			)
		)
		(property "Datasheet" "https://www.murata.com/products/productdetail?partno=GRM155R61H104KE14%23"
			(at 64.77 30.48 0)
			(effects
				(font
					(size 1.27 1.27)
					(thickness 0.15)
				)
				(justify left bottom)
				(hide yes)
			)
		)
		(property "Description" ""
			(at 49.53 50.8 0)
			(effects
				(font
					(size 1.27 1.27)
				)
				(hide yes)
			)
		)
		(property "Manufacturer" "Murata"
			(at 69.85 30.48 0)
			(effects
				(font
					(size 1.27 1.27)
					(thickness 0.15)
				)
				(justify left bottom)
				(hide yes)
			)
		)
		(property "MPN" "GRM155R61H104KE14D"
			(at 67.31 30.48 0)
			(effects
				(font
					(size 1.27 1.27)
					(thickness 0.15)
				)
				(justify left bottom)
				(hide yes)
			)
		)
		(property "Val" "100n"
			(at 52.07 49.5236 90)
			(effects
				(font
					(size 1.27 1.27)
					(thickness 0.15)
				)
				(justify right)
			)
		)
		(property "License" "Apache-2.0"
			(at 72.39 30.48 0)
			(effects
				(font
					(size 1.27 1.27)
					(thickness 0.15)
				)
				(justify left bottom)
				(hide yes)
			)
		)
		(property "Author" "Antmicro"
			(at 74.93 30.48 0)
			(effects
				(font
					(size 1.27 1.27)
					(thickness 0.15)
				)
				(justify left bottom)
				(hide yes)
			)
		)
		(property "Voltage" "50V"
			(at 77.47 30.48 0)
			(effects
				(font
					(size 1.27 1.27)
				)
				(justify left bottom)
				(hide yes)
			)
		)
		(property "Dielectric" "X5R"
			(at 80.01 30.48 0)
			(effects
				(font
					(size 1.27 1.27)
				)
				(justify left bottom)
				(hide yes)
			)
		)
		(pin "1"
		)
		(pin "2"
		)
		(instances
			(project "jetson-orin-baseboard"
				(path ""
					(reference "C89")
					(unit 1)
				)
			)
		)
	)
	(symbol
		(lib_id "antmicroResistors0402:R_0R_0402")
		(at 40.64 63.5 0)
		(mirror y)
		(unit 1)
		(exclude_from_sim no)
		(in_bom yes)
		(on_board yes)
		(dnp no)
		(property "Reference" "R162"
			(at 40.64 62.865 0)
			(effects
				(font
					(size 1.27 1.27)
				)
				(justify right bottom)
			)
		)
		(property "Value" "R_0R_0402"
			(at 20.32 76.2 0)
			(effects
				(font
					(size 1.27 1.27)
					(thickness 0.15)
				)
				(justify left bottom)
				(hide yes)
			)
		)
		(property "Footprint" "antmicro-footprints:R_0402_1005Metric"
			(at 20.32 78.74 0)
			(effects
				(font
					(size 1.27 1.27)
					(thickness 0.15)
				)
				(justify left bottom)
				(hide yes)
			)
		)
		(property "Datasheet" "https://industrial.panasonic.com/cdbs/www-data/pdf/RDA0000/AOA0000C301.pdf"
			(at 20.32 81.28 0)
			(effects
				(font
					(size 1.27 1.27)
					(thickness 0.15)
				)
				(justify left bottom)
				(hide yes)
			)
		)
		(property "Description" ""
			(at 40.64 63.5 0)
			(effects
				(font
					(size 1.27 1.27)
				)
				(hide yes)
			)
		)
		(property "Manufacturer" "Panasonic"
			(at 20.32 86.36 0)
			(effects
				(font
					(size 1.27 1.27)
					(thickness 0.15)
				)
				(justify left bottom)
				(hide yes)
			)
		)
		(property "MPN" "ERJ2GE0R00X"
			(at 20.32 83.82 0)
			(effects
				(font
					(size 1.27 1.27)
					(thickness 0.15)
				)
				(justify left bottom)
				(hide yes)
			)
		)
		(property "Val" "0R"
			(at 33.02 62.865 0)
			(effects
				(font
					(size 1.27 1.27)
					(thickness 0.15)
				)
				(justify right bottom)
			)
		)
		(property "License" "Apache-2.0"
			(at 20.32 88.9 0)
			(effects
				(font
					(size 1.27 1.27)
					(thickness 0.15)
				)
				(justify left bottom)
				(hide yes)
			)
		)
		(property "Author" "Antmicro"
			(at 20.32 91.44 0)
			(effects
				(font
					(size 1.27 1.27)
					(thickness 0.15)
				)
				(justify left bottom)
				(hide yes)
			)
		)
		(property "Tolerance" "~"
			(at 20.32 73.66 0)
			(effects
				(font
					(size 1.27 1.27)
				)
				(justify left bottom)
				(hide yes)
			)
		)
		(property "Current" "1A"
			(at 20.32 93.98 0)
			(effects
				(font
					(size 1.27 1.27)
					(thickness 0.15)
				)
				(justify left bottom)
				(hide yes)
			)
		)
		(pin "1"
		)
		(pin "2"
		)
		(instances
			(project "jetson-orin-baseboard"
				(path ""
					(reference "R162")
					(unit 1)
				)
			)
		)
	)
	(symbol
		(lib_id "antmicropower:+1V8")
		(at 72.39 129.54 0)
		(unit 1)
		(exclude_from_sim no)
		(in_bom yes)
		(on_board yes)
		(dnp no)
		(property "Reference" "#PWR0332"
			(at 72.39 133.35 0)
			(effects
				(font
					(size 1.27 1.27)
				)
				(justify left bottom)
				(hide yes)
			)
		)
		(property "Value" "+1V8"
			(at 71.755 125.73 0)
			(effects
				(font
					(size 1.27 1.27)
					(thickness 0.15)
				)
			)
		)
		(property "Footprint" ""
			(at 87.63 137.16 0)
			(effects
				(font
					(size 1.27 1.27)
					(thickness 0.15)
				)
				(justify left bottom)
				(hide yes)
			)
		)
		(property "Datasheet" ""
			(at 87.63 139.7 0)
			(effects
				(font
					(size 1.27 1.27)
					(thickness 0.15)
				)
				(justify left bottom)
				(hide yes)
			)
		)
		(property "Description" ""
			(at 72.39 129.54 0)
			(effects
				(font
					(size 1.27 1.27)
				)
				(hide yes)
			)
		)
		(property "Author" "Antmicro"
			(at 87.63 134.62 0)
			(effects
				(font
					(size 1.27 1.27)
					(thickness 0.15)
				)
				(justify left bottom)
				(hide yes)
			)
		)
		(property "License" "Apache-2.0"
			(at 87.63 137.16 0)
			(effects
				(font
					(size 1.27 1.27)
					(thickness 0.15)
				)
				(justify left bottom)
				(hide yes)
			)
		)
		(pin "1"
		)
		(instances
			(project "jetson-orin-baseboard"
				(path ""
					(reference "#PWR0332")
					(unit 1)
				)
			)
		)
	)
	(symbol
		(lib_id "antmicroTestPoints:TP_0.75mm_SMD")
		(at 97.79 104.14 0)
		(unit 1)
		(exclude_from_sim no)
		(in_bom no)
		(on_board yes)
		(dnp no)
		(property "Reference" "TP43"
			(at 101.6 104.1399 0)
			(effects
				(font
					(size 1.27 1.27)
				)
				(justify left)
			)
		)
		(property "Value" "TP_0.75mm_SMD"
			(at 107.95 107.95 0)
			(effects
				(font
					(size 1.27 1.27)
					(thickness 0.15)
				)
				(justify left bottom)
				(hide yes)
			)
		)
		(property "Footprint" "antmicro-footprints:TP_SMD_0.75mm"
			(at 107.95 110.49 0)
			(effects
				(font
					(size 1.27 1.27)
					(thickness 0.15)
				)
				(justify left bottom)
				(hide yes)
			)
		)
		(property "Datasheet" ""
			(at 115.57 116.84 0)
			(effects
				(font
					(size 1.27 1.27)
					(thickness 0.15)
				)
				(justify left bottom)
				(hide yes)
			)
		)
		(property "Description" ""
			(at 97.79 104.14 0)
			(effects
				(font
					(size 1.27 1.27)
				)
				(hide yes)
			)
		)
		(property "MPN" ""
			(at 108.585 115.57 0)
			(effects
				(font
					(size 1.27 1.27)
					(thickness 0.15)
				)
				(justify left bottom)
				(hide yes)
			)
		)
		(property "Manufacturer" ""
			(at 108.585 110.49 0)
			(effects
				(font
					(size 1.27 1.27)
					(thickness 0.15)
				)
				(justify left bottom)
				(hide yes)
			)
		)
		(property "Author" "Antmicro"
			(at 107.95 113.03 0)
			(effects
				(font
					(size 1.27 1.27)
					(thickness 0.15)
				)
				(justify left bottom)
				(hide yes)
			)
		)
		(property "License" "Apache-2.0"
			(at 107.95 115.57 0)
			(effects
				(font
					(size 1.27 1.27)
					(thickness 0.15)
				)
				(justify left bottom)
				(hide yes)
			)
		)
		(pin "1"
		)
		(instances
			(project "jetson-orin-baseboard"
				(path ""
					(reference "TP43")
					(unit 1)
				)
			)
		)
	)
	(symbol
		(lib_id "antmicroPMICPowerDistributionSwitchesLoadDrivers:AP22615A_TSOT26")
		(at 201.93 210.82 0)
		(unit 1)
		(exclude_from_sim no)
		(in_bom yes)
		(on_board yes)
		(dnp no)
		(property "Reference" "U27"
			(at 209.55 204.47 0)
			(effects
				(font
					(size 1.27 1.27)
				)
			)
		)
		(property "Value" "AP22615A_TSOT26"
			(at 232.41 215.9 0)
			(effects
				(font
					(size 1.27 1.27)
					(thickness 0.15)
				)
				(justify left bottom)
				(hide yes)
			)
		)
		(property "Footprint" "antmicro-footprints:TSOT23-6"
			(at 232.41 218.44 0)
			(effects
				(font
					(size 1.27 1.27)
					(thickness 0.15)
				)
				(justify left bottom)
				(hide yes)
			)
		)
		(property "Datasheet" "https://www.mouser.com/datasheet/2/115/DIOD_S_A0008958405_1-2543193.pdf"
			(at 232.41 220.98 0)
			(effects
				(font
					(size 1.27 1.27)
					(thickness 0.15)
				)
				(justify left bottom)
				(hide yes)
			)
		)
		(property "Description" ""
			(at 201.93 210.82 0)
			(effects
				(font
					(size 1.27 1.27)
				)
				(hide yes)
			)
		)
		(property "MPN" "AP22615AWU-7"
			(at 209.55 207.01 0)
			(effects
				(font
					(size 1.27 1.27)
					(thickness 0.15)
				)
			)
		)
		(property "Manufacturer" "Diodes Incorporated"
			(at 232.41 226.06 0)
			(effects
				(font
					(size 1.27 1.27)
					(thickness 0.15)
				)
				(justify left bottom)
				(hide yes)
			)
		)
		(property "Author" "Antmicro"
			(at 232.41 228.6 0)
			(effects
				(font
					(size 1.27 1.27)
					(thickness 0.15)
				)
				(justify left bottom)
				(hide yes)
			)
		)
		(property "License" "Apache-2.0"
			(at 232.41 231.14 0)
			(effects
				(font
					(size 1.27 1.27)
					(thickness 0.15)
				)
				(justify left bottom)
				(hide yes)
			)
		)
		(pin "1"
		)
		(pin "2"
		)
		(pin "3"
		)
		(pin "4"
		)
		(pin "5"
		)
		(pin "6"
		)
		(instances
			(project "jetson-orin-baseboard"
				(path ""
					(reference "U27")
					(unit 1)
				)
			)
		)
	)
	(symbol
		(lib_id "antmicropower:GND")
		(at 271.78 162.56 0)
		(unit 1)
		(exclude_from_sim no)
		(in_bom yes)
		(on_board yes)
		(dnp no)
		(property "Reference" "#PWR0191"
			(at 271.78 168.91 0)
			(effects
				(font
					(size 1.27 1.27)
				)
				(justify left bottom)
				(hide yes)
			)
		)
		(property "Value" "GND"
			(at 271.78 166.37 0)
			(effects
				(font
					(size 1.27 1.27)
					(thickness 0.15)
				)
			)
		)
		(property "Footprint" ""
			(at 280.67 170.18 0)
			(effects
				(font
					(size 1.27 1.27)
					(thickness 0.15)
				)
				(justify left bottom)
				(hide yes)
			)
		)
		(property "Datasheet" ""
			(at 280.67 175.26 0)
			(effects
				(font
					(size 1.27 1.27)
					(thickness 0.15)
				)
				(justify left bottom)
				(hide yes)
			)
		)
		(property "Description" ""
			(at 271.78 162.56 0)
			(effects
				(font
					(size 1.27 1.27)
				)
				(hide yes)
			)
		)
		(property "Author" "Antmicro"
			(at 280.67 170.18 0)
			(effects
				(font
					(size 1.27 1.27)
					(thickness 0.15)
				)
				(justify left bottom)
				(hide yes)
			)
		)
		(property "License" "Apache-2.0"
			(at 280.67 172.72 0)
			(effects
				(font
					(size 1.27 1.27)
					(thickness 0.15)
				)
				(justify left bottom)
				(hide yes)
			)
		)
		(pin "1"
		)
		(instances
			(project "jetson-orin-baseboard"
				(path ""
					(reference "#PWR0191")
					(unit 1)
				)
			)
		)
	)
	(symbol
		(lib_id "antmicroResistors0402:R_10k_0402")
		(at 66.04 208.28 90)
		(unit 1)
		(exclude_from_sim no)
		(in_bom no)
		(on_board yes)
		(dnp yes)
		(property "Reference" "R193"
			(at 67.31 204.47 90)
			(effects
				(font
					(size 1.27 1.27)
				)
				(justify right)
			)
		)
		(property "Value" "R_10k_0402"
			(at 78.74 187.96 0)
			(effects
				(font
					(size 1.27 1.27)
					(thickness 0.15)
				)
				(justify left bottom)
				(hide yes)
			)
		)
		(property "Footprint" "antmicro-footprints:R_0402_1005Metric"
			(at 81.28 187.96 0)
			(effects
				(font
					(size 1.27 1.27)
					(thickness 0.15)
				)
				(justify left bottom)
				(hide yes)
			)
		)
		(property "Datasheet" "https://www.bourns.com/docs/product-datasheets/cr.pdf"
			(at 83.82 187.96 0)
			(effects
				(font
					(size 1.27 1.27)
					(thickness 0.15)
				)
				(justify left bottom)
				(hide yes)
			)
		)
		(property "Description" ""
			(at 66.04 208.28 0)
			(effects
				(font
					(size 1.27 1.27)
				)
				(hide yes)
			)
		)
		(property "Manufacturer" "Bourns"
			(at 88.9 187.96 0)
			(effects
				(font
					(size 1.27 1.27)
					(thickness 0.15)
				)
				(justify left bottom)
				(hide yes)
			)
		)
		(property "MPN" "CR0402-FX-1002GLF"
			(at 86.36 187.96 0)
			(effects
				(font
					(size 1.27 1.27)
					(thickness 0.15)
				)
				(justify left bottom)
				(hide yes)
			)
		)
		(property "Val" "10k"
			(at 67.31 207.01 90)
			(effects
				(font
					(size 1.27 1.27)
					(thickness 0.15)
				)
				(justify right)
			)
		)
		(property "License" "Apache-2.0"
			(at 91.44 187.96 0)
			(effects
				(font
					(size 1.27 1.27)
					(thickness 0.15)
				)
				(justify left bottom)
				(hide yes)
			)
		)
		(property "Author" "Antmicro"
			(at 93.98 187.96 0)
			(effects
				(font
					(size 1.27 1.27)
					(thickness 0.15)
				)
				(justify left bottom)
				(hide yes)
			)
		)
		(property "Tolerance" "1%"
			(at 76.2 187.96 0)
			(effects
				(font
					(size 1.27 1.27)
				)
				(justify left bottom)
				(hide yes)
			)
		)
		(pin "1"
		)
		(pin "2"
		)
		(instances
			(project "jetson-orin-baseboard"
				(path ""
					(reference "R193")
					(unit 1)
				)
			)
		)
	)
	(symbol
		(lib_id "antmicropower:+1V8")
		(at 35.56 74.93 0)
		(unit 1)
		(exclude_from_sim no)
		(in_bom yes)
		(on_board yes)
		(dnp no)
		(property "Reference" "#PWR0154"
			(at 35.56 78.74 0)
			(effects
				(font
					(size 1.27 1.27)
				)
				(justify left bottom)
				(hide yes)
			)
		)
		(property "Value" "+1V8"
			(at 32.385 71.12 0)
			(effects
				(font
					(size 1.27 1.27)
					(thickness 0.15)
				)
				(justify left)
			)
		)
		(property "Footprint" ""
			(at 50.8 82.55 0)
			(effects
				(font
					(size 1.27 1.27)
					(thickness 0.15)
				)
				(justify left bottom)
				(hide yes)
			)
		)
		(property "Datasheet" ""
			(at 50.8 85.09 0)
			(effects
				(font
					(size 1.27 1.27)
					(thickness 0.15)
				)
				(justify left bottom)
				(hide yes)
			)
		)
		(property "Description" ""
			(at 35.56 74.93 0)
			(effects
				(font
					(size 1.27 1.27)
				)
				(hide yes)
			)
		)
		(property "Author" "Antmicro"
			(at 50.8 80.01 0)
			(effects
				(font
					(size 1.27 1.27)
					(thickness 0.15)
				)
				(justify left bottom)
				(hide yes)
			)
		)
		(property "License" "Apache-2.0"
			(at 50.8 82.55 0)
			(effects
				(font
					(size 1.27 1.27)
					(thickness 0.15)
				)
				(justify left bottom)
				(hide yes)
			)
		)
		(pin "1"
		)
		(instances
			(project "jetson-orin-baseboard"
				(path ""
					(reference "#PWR0154")
					(unit 1)
				)
			)
		)
	)
	(symbol
		(lib_id "antmicropower:GND")
		(at 364.49 218.44 0)
		(unit 1)
		(exclude_from_sim no)
		(in_bom yes)
		(on_board yes)
		(dnp no)
		(property "Reference" "#PWR0169"
			(at 364.49 224.79 0)
			(effects
				(font
					(size 1.27 1.27)
				)
				(justify left bottom)
				(hide yes)
			)
		)
		(property "Value" "GND"
			(at 364.49 222.25 0)
			(effects
				(font
					(size 1.27 1.27)
					(thickness 0.15)
				)
			)
		)
		(property "Footprint" ""
			(at 373.38 226.06 0)
			(effects
				(font
					(size 1.27 1.27)
					(thickness 0.15)
				)
				(justify left bottom)
				(hide yes)
			)
		)
		(property "Datasheet" ""
			(at 373.38 231.14 0)
			(effects
				(font
					(size 1.27 1.27)
					(thickness 0.15)
				)
				(justify left bottom)
				(hide yes)
			)
		)
		(property "Description" ""
			(at 364.49 218.44 0)
			(effects
				(font
					(size 1.27 1.27)
				)
				(hide yes)
			)
		)
		(property "Author" "Antmicro"
			(at 373.38 226.06 0)
			(effects
				(font
					(size 1.27 1.27)
					(thickness 0.15)
				)
				(justify left bottom)
				(hide yes)
			)
		)
		(property "License" "Apache-2.0"
			(at 373.38 228.6 0)
			(effects
				(font
					(size 1.27 1.27)
					(thickness 0.15)
				)
				(justify left bottom)
				(hide yes)
			)
		)
		(pin "1"
		)
		(instances
			(project "jetson-orin-baseboard"
				(path ""
					(reference "#PWR0169")
					(unit 1)
				)
			)
		)
	)
	(symbol
		(lib_id "antmicropower:GND")
		(at 266.7 162.56 0)
		(unit 1)
		(exclude_from_sim no)
		(in_bom yes)
		(on_board yes)
		(dnp no)
		(property "Reference" "#PWR0188"
			(at 266.7 168.91 0)
			(effects
				(font
					(size 1.27 1.27)
				)
				(justify left bottom)
				(hide yes)
			)
		)
		(property "Value" "GND"
			(at 266.7 166.37 0)
			(effects
				(font
					(size 1.27 1.27)
					(thickness 0.15)
				)
			)
		)
		(property "Footprint" ""
			(at 275.59 170.18 0)
			(effects
				(font
					(size 1.27 1.27)
					(thickness 0.15)
				)
				(justify left bottom)
				(hide yes)
			)
		)
		(property "Datasheet" ""
			(at 275.59 175.26 0)
			(effects
				(font
					(size 1.27 1.27)
					(thickness 0.15)
				)
				(justify left bottom)
				(hide yes)
			)
		)
		(property "Description" ""
			(at 266.7 162.56 0)
			(effects
				(font
					(size 1.27 1.27)
				)
				(hide yes)
			)
		)
		(property "Author" "Antmicro"
			(at 275.59 170.18 0)
			(effects
				(font
					(size 1.27 1.27)
					(thickness 0.15)
				)
				(justify left bottom)
				(hide yes)
			)
		)
		(property "License" "Apache-2.0"
			(at 275.59 172.72 0)
			(effects
				(font
					(size 1.27 1.27)
					(thickness 0.15)
				)
				(justify left bottom)
				(hide yes)
			)
		)
		(pin "1"
		)
		(instances
			(project "jetson-orin-baseboard"
				(path ""
					(reference "#PWR0188")
					(unit 1)
				)
			)
		)
	)
	(symbol
		(lib_id "antmicroCapacitors0402:C_1u_0402")
		(at 344.17 161.29 90)
		(unit 1)
		(exclude_from_sim no)
		(in_bom yes)
		(on_board yes)
		(dnp no)
		(fields_autoplaced yes)
		(property "Reference" "C98"
			(at 341.63 157.4736 90)
			(effects
				(font
					(size 1.27 1.27)
				)
				(justify left)
			)
		)
		(property "Value" "C_1u_0402"
			(at 354.33 140.97 0)
			(effects
				(font
					(size 1.27 1.27)
					(thickness 0.15)
				)
				(justify left bottom)
				(hide yes)
			)
		)
		(property "Footprint" "antmicro-footprints:C_0402_1005Metric"
			(at 356.87 140.97 0)
			(effects
				(font
					(size 1.27 1.27)
					(thickness 0.15)
				)
				(justify left bottom)
				(hide yes)
			)
		)
		(property "Datasheet" "https://product.tdk.com/en/search/capacitor/ceramic/mlcc/info?part_no=C1005X6S1A105K050BC"
			(at 359.41 140.97 0)
			(effects
				(font
					(size 1.27 1.27)
					(thickness 0.15)
				)
				(justify left bottom)
				(hide yes)
			)
		)
		(property "Description" ""
			(at 344.17 161.29 0)
			(effects
				(font
					(size 1.27 1.27)
				)
				(hide yes)
			)
		)
		(property "Manufacturer" "TDK"
			(at 364.49 140.97 0)
			(effects
				(font
					(size 1.27 1.27)
					(thickness 0.15)
				)
				(justify left bottom)
				(hide yes)
			)
		)
		(property "MPN" "C1005X6S1A105K050BC"
			(at 361.95 140.97 0)
			(effects
				(font
					(size 1.27 1.27)
					(thickness 0.15)
				)
				(justify left bottom)
				(hide yes)
			)
		)
		(property "Val" "1u"
			(at 341.63 160.0136 90)
			(effects
				(font
					(size 1.27 1.27)
					(thickness 0.15)
				)
				(justify left)
			)
		)
		(property "License" "Apache-2.0"
			(at 367.03 140.97 0)
			(effects
				(font
					(size 1.27 1.27)
					(thickness 0.15)
				)
				(justify left bottom)
				(hide yes)
			)
		)
		(property "Author" "Antmicro"
			(at 369.57 140.97 0)
			(effects
				(font
					(size 1.27 1.27)
					(thickness 0.15)
				)
				(justify left bottom)
				(hide yes)
			)
		)
		(property "Voltage" ""
			(at 372.11 140.97 0)
			(effects
				(font
					(size 1.27 1.27)
				)
				(justify left bottom)
				(hide yes)
			)
		)
		(property "Dielectric" ""
			(at 374.65 140.97 0)
			(effects
				(font
					(size 1.27 1.27)
				)
				(justify left bottom)
				(hide yes)
			)
		)
		(pin "1"
		)
		(pin "2"
		)
		(instances
			(project "jetson-orin-baseboard"
				(path ""
					(reference "C98")
					(unit 1)
				)
			)
		)
	)
	(symbol
		(lib_id "antmicropower:GND")
		(at 284.48 163.83 0)
		(unit 1)
		(exclude_from_sim no)
		(in_bom yes)
		(on_board yes)
		(dnp no)
		(property "Reference" "#PWR0198"
			(at 284.48 170.18 0)
			(effects
				(font
					(size 1.27 1.27)
				)
				(justify left bottom)
				(hide yes)
			)
		)
		(property "Value" "GND"
			(at 284.48 167.64 0)
			(effects
				(font
					(size 1.27 1.27)
					(thickness 0.15)
				)
			)
		)
		(property "Footprint" ""
			(at 293.37 171.45 0)
			(effects
				(font
					(size 1.27 1.27)
					(thickness 0.15)
				)
				(justify left bottom)
				(hide yes)
			)
		)
		(property "Datasheet" ""
			(at 293.37 176.53 0)
			(effects
				(font
					(size 1.27 1.27)
					(thickness 0.15)
				)
				(justify left bottom)
				(hide yes)
			)
		)
		(property "Description" ""
			(at 284.48 163.83 0)
			(effects
				(font
					(size 1.27 1.27)
				)
				(hide yes)
			)
		)
		(property "Author" "Antmicro"
			(at 293.37 171.45 0)
			(effects
				(font
					(size 1.27 1.27)
					(thickness 0.15)
				)
				(justify left bottom)
				(hide yes)
			)
		)
		(property "License" "Apache-2.0"
			(at 293.37 173.99 0)
			(effects
				(font
					(size 1.27 1.27)
					(thickness 0.15)
				)
				(justify left bottom)
				(hide yes)
			)
		)
		(pin "1"
		)
		(instances
			(project "jetson-orin-baseboard"
				(path ""
					(reference "#PWR0198")
					(unit 1)
				)
			)
		)
	)
	(symbol
		(lib_id "antmicropower:GND")
		(at 372.11 204.47 0)
		(unit 1)
		(exclude_from_sim no)
		(in_bom yes)
		(on_board yes)
		(dnp no)
		(property "Reference" "#PWR0167"
			(at 372.11 210.82 0)
			(effects
				(font
					(size 1.27 1.27)
				)
				(justify left bottom)
				(hide yes)
			)
		)
		(property "Value" "GND"
			(at 372.11 208.28 0)
			(effects
				(font
					(size 1.27 1.27)
					(thickness 0.15)
				)
			)
		)
		(property "Footprint" ""
			(at 381 212.09 0)
			(effects
				(font
					(size 1.27 1.27)
					(thickness 0.15)
				)
				(justify left bottom)
				(hide yes)
			)
		)
		(property "Datasheet" ""
			(at 381 217.17 0)
			(effects
				(font
					(size 1.27 1.27)
					(thickness 0.15)
				)
				(justify left bottom)
				(hide yes)
			)
		)
		(property "Description" ""
			(at 372.11 204.47 0)
			(effects
				(font
					(size 1.27 1.27)
				)
				(hide yes)
			)
		)
		(property "Author" "Antmicro"
			(at 381 212.09 0)
			(effects
				(font
					(size 1.27 1.27)
					(thickness 0.15)
				)
				(justify left bottom)
				(hide yes)
			)
		)
		(property "License" "Apache-2.0"
			(at 381 214.63 0)
			(effects
				(font
					(size 1.27 1.27)
					(thickness 0.15)
				)
				(justify left bottom)
				(hide yes)
			)
		)
		(pin "1"
		)
		(instances
			(project "jetson-orin-baseboard"
				(path ""
					(reference "#PWR0167")
					(unit 1)
				)
			)
		)
	)
	(symbol
		(lib_id "antmicropower:GND")
		(at 323.85 168.91 0)
		(unit 1)
		(exclude_from_sim no)
		(in_bom yes)
		(on_board yes)
		(dnp no)
		(property "Reference" "#PWR0205"
			(at 323.85 175.26 0)
			(effects
				(font
					(size 1.27 1.27)
				)
				(justify left bottom)
				(hide yes)
			)
		)
		(property "Value" "GND"
			(at 323.85 172.72 0)
			(effects
				(font
					(size 1.27 1.27)
					(thickness 0.15)
				)
			)
		)
		(property "Footprint" ""
			(at 332.74 176.53 0)
			(effects
				(font
					(size 1.27 1.27)
					(thickness 0.15)
				)
				(justify left bottom)
				(hide yes)
			)
		)
		(property "Datasheet" ""
			(at 332.74 181.61 0)
			(effects
				(font
					(size 1.27 1.27)
					(thickness 0.15)
				)
				(justify left bottom)
				(hide yes)
			)
		)
		(property "Description" ""
			(at 323.85 168.91 0)
			(effects
				(font
					(size 1.27 1.27)
				)
				(hide yes)
			)
		)
		(property "Author" "Antmicro"
			(at 332.74 176.53 0)
			(effects
				(font
					(size 1.27 1.27)
					(thickness 0.15)
				)
				(justify left bottom)
				(hide yes)
			)
		)
		(property "License" "Apache-2.0"
			(at 332.74 179.07 0)
			(effects
				(font
					(size 1.27 1.27)
					(thickness 0.15)
				)
				(justify left bottom)
				(hide yes)
			)
		)
		(pin "1"
		)
		(instances
			(project "jetson-orin-baseboard"
				(path ""
					(reference "#PWR0205")
					(unit 1)
				)
			)
		)
	)
	(symbol
		(lib_id "antmicroTestPoints:TP_0.75mm_SMD")
		(at 97.79 81.28 0)
		(unit 1)
		(exclude_from_sim no)
		(in_bom no)
		(on_board yes)
		(dnp no)
		(property "Reference" "TP37"
			(at 104.14 81.28 0)
			(effects
				(font
					(size 1.27 1.27)
				)
			)
		)
		(property "Value" "TP_0.75mm_SMD"
			(at 107.95 85.09 0)
			(effects
				(font
					(size 1.27 1.27)
					(thickness 0.15)
				)
				(justify left bottom)
				(hide yes)
			)
		)
		(property "Footprint" "antmicro-footprints:TP_SMD_0.75mm"
			(at 107.95 87.63 0)
			(effects
				(font
					(size 1.27 1.27)
					(thickness 0.15)
				)
				(justify left bottom)
				(hide yes)
			)
		)
		(property "Datasheet" ""
			(at 115.57 93.98 0)
			(effects
				(font
					(size 1.27 1.27)
					(thickness 0.15)
				)
				(justify left bottom)
				(hide yes)
			)
		)
		(property "Description" ""
			(at 97.79 81.28 0)
			(effects
				(font
					(size 1.27 1.27)
				)
				(hide yes)
			)
		)
		(property "MPN" ""
			(at 108.585 92.71 0)
			(effects
				(font
					(size 1.27 1.27)
					(thickness 0.15)
				)
				(justify left bottom)
				(hide yes)
			)
		)
		(property "Manufacturer" ""
			(at 108.585 87.63 0)
			(effects
				(font
					(size 1.27 1.27)
					(thickness 0.15)
				)
				(justify left bottom)
				(hide yes)
			)
		)
		(property "Author" "Antmicro"
			(at 107.95 90.17 0)
			(effects
				(font
					(size 1.27 1.27)
					(thickness 0.15)
				)
				(justify left bottom)
				(hide yes)
			)
		)
		(property "License" "Apache-2.0"
			(at 107.95 92.71 0)
			(effects
				(font
					(size 1.27 1.27)
					(thickness 0.15)
				)
				(justify left bottom)
				(hide yes)
			)
		)
		(pin "1"
		)
		(instances
			(project "jetson-orin-baseboard"
				(path ""
					(reference "TP37")
					(unit 1)
				)
			)
		)
	)
	(symbol
		(lib_id "antmicroCapacitors0402:C_1u_0402")
		(at 266.7 161.29 90)
		(unit 1)
		(exclude_from_sim no)
		(in_bom yes)
		(on_board yes)
		(dnp no)
		(fields_autoplaced yes)
		(property "Reference" "C94"
			(at 264.16 157.4736 90)
			(effects
				(font
					(size 1.27 1.27)
				)
				(justify left)
			)
		)
		(property "Value" "C_1u_0402"
			(at 276.86 140.97 0)
			(effects
				(font
					(size 1.27 1.27)
					(thickness 0.15)
				)
				(justify left bottom)
				(hide yes)
			)
		)
		(property "Footprint" "antmicro-footprints:C_0402_1005Metric"
			(at 279.4 140.97 0)
			(effects
				(font
					(size 1.27 1.27)
					(thickness 0.15)
				)
				(justify left bottom)
				(hide yes)
			)
		)
		(property "Datasheet" "https://product.tdk.com/en/search/capacitor/ceramic/mlcc/info?part_no=C1005X6S1A105K050BC"
			(at 281.94 140.97 0)
			(effects
				(font
					(size 1.27 1.27)
					(thickness 0.15)
				)
				(justify left bottom)
				(hide yes)
			)
		)
		(property "Description" ""
			(at 266.7 161.29 0)
			(effects
				(font
					(size 1.27 1.27)
				)
				(hide yes)
			)
		)
		(property "Manufacturer" "TDK"
			(at 287.02 140.97 0)
			(effects
				(font
					(size 1.27 1.27)
					(thickness 0.15)
				)
				(justify left bottom)
				(hide yes)
			)
		)
		(property "MPN" "C1005X6S1A105K050BC"
			(at 284.48 140.97 0)
			(effects
				(font
					(size 1.27 1.27)
					(thickness 0.15)
				)
				(justify left bottom)
				(hide yes)
			)
		)
		(property "Val" "1u"
			(at 264.16 160.0136 90)
			(effects
				(font
					(size 1.27 1.27)
					(thickness 0.15)
				)
				(justify left)
			)
		)
		(property "License" "Apache-2.0"
			(at 289.56 140.97 0)
			(effects
				(font
					(size 1.27 1.27)
					(thickness 0.15)
				)
				(justify left bottom)
				(hide yes)
			)
		)
		(property "Author" "Antmicro"
			(at 292.1 140.97 0)
			(effects
				(font
					(size 1.27 1.27)
					(thickness 0.15)
				)
				(justify left bottom)
				(hide yes)
			)
		)
		(property "Voltage" ""
			(at 294.64 140.97 0)
			(effects
				(font
					(size 1.27 1.27)
				)
				(justify left bottom)
				(hide yes)
			)
		)
		(property "Dielectric" ""
			(at 297.18 140.97 0)
			(effects
				(font
					(size 1.27 1.27)
				)
				(justify left bottom)
				(hide yes)
			)
		)
		(pin "1"
		)
		(pin "2"
		)
		(instances
			(project "jetson-orin-baseboard"
				(path ""
					(reference "C94")
					(unit 1)
				)
			)
		)
	)
	(symbol
		(lib_id "antmicropower:GND")
		(at 185.42 209.55 0)
		(unit 1)
		(exclude_from_sim no)
		(in_bom yes)
		(on_board yes)
		(dnp no)
		(property "Reference" "#PWR0221"
			(at 185.42 215.9 0)
			(effects
				(font
					(size 1.27 1.27)
				)
				(justify left bottom)
				(hide yes)
			)
		)
		(property "Value" "GND"
			(at 185.42 213.36 0)
			(effects
				(font
					(size 1.27 1.27)
					(thickness 0.15)
				)
			)
		)
		(property "Footprint" ""
			(at 194.31 217.17 0)
			(effects
				(font
					(size 1.27 1.27)
					(thickness 0.15)
				)
				(justify left bottom)
				(hide yes)
			)
		)
		(property "Datasheet" ""
			(at 194.31 222.25 0)
			(effects
				(font
					(size 1.27 1.27)
					(thickness 0.15)
				)
				(justify left bottom)
				(hide yes)
			)
		)
		(property "Description" ""
			(at 185.42 209.55 0)
			(effects
				(font
					(size 1.27 1.27)
				)
				(hide yes)
			)
		)
		(property "Author" "Antmicro"
			(at 194.31 217.17 0)
			(effects
				(font
					(size 1.27 1.27)
					(thickness 0.15)
				)
				(justify left bottom)
				(hide yes)
			)
		)
		(property "License" "Apache-2.0"
			(at 194.31 219.71 0)
			(effects
				(font
					(size 1.27 1.27)
					(thickness 0.15)
				)
				(justify left bottom)
				(hide yes)
			)
		)
		(pin "1"
		)
		(instances
			(project "jetson-orin-baseboard"
				(path ""
					(reference "#PWR0221")
					(unit 1)
				)
			)
		)
	)
	(symbol
		(lib_id "antmicroPMICPowerDistributionSwitchesLoadDrivers:AP22615A_TSOT26")
		(at 92.71 210.82 0)
		(unit 1)
		(exclude_from_sim no)
		(in_bom yes)
		(on_board yes)
		(dnp no)
		(property "Reference" "U24"
			(at 100.33 204.47 0)
			(effects
				(font
					(size 1.27 1.27)
				)
			)
		)
		(property "Value" "AP22615A_TSOT26"
			(at 123.19 215.9 0)
			(effects
				(font
					(size 1.27 1.27)
					(thickness 0.15)
				)
				(justify left bottom)
				(hide yes)
			)
		)
		(property "Footprint" "antmicro-footprints:TSOT23-6"
			(at 123.19 218.44 0)
			(effects
				(font
					(size 1.27 1.27)
					(thickness 0.15)
				)
				(justify left bottom)
				(hide yes)
			)
		)
		(property "Datasheet" "https://www.mouser.com/datasheet/2/115/DIOD_S_A0008958405_1-2543193.pdf"
			(at 123.19 220.98 0)
			(effects
				(font
					(size 1.27 1.27)
					(thickness 0.15)
				)
				(justify left bottom)
				(hide yes)
			)
		)
		(property "Description" ""
			(at 92.71 210.82 0)
			(effects
				(font
					(size 1.27 1.27)
				)
				(hide yes)
			)
		)
		(property "MPN" "AP22615AWU-7"
			(at 100.33 207.01 0)
			(effects
				(font
					(size 1.27 1.27)
					(thickness 0.15)
				)
			)
		)
		(property "Manufacturer" "Diodes Incorporated"
			(at 123.19 226.06 0)
			(effects
				(font
					(size 1.27 1.27)
					(thickness 0.15)
				)
				(justify left bottom)
				(hide yes)
			)
		)
		(property "Author" "Antmicro"
			(at 123.19 228.6 0)
			(effects
				(font
					(size 1.27 1.27)
					(thickness 0.15)
				)
				(justify left bottom)
				(hide yes)
			)
		)
		(property "License" "Apache-2.0"
			(at 123.19 231.14 0)
			(effects
				(font
					(size 1.27 1.27)
					(thickness 0.15)
				)
				(justify left bottom)
				(hide yes)
			)
		)
		(pin "1"
		)
		(pin "2"
		)
		(pin "3"
		)
		(pin "4"
		)
		(pin "5"
		)
		(pin "6"
		)
		(instances
			(project "jetson-orin-baseboard"
				(path ""
					(reference "U24")
					(unit 1)
				)
			)
		)
	)
	(symbol
		(lib_id "antmicropower:GND")
		(at 372.11 234.95 0)
		(unit 1)
		(exclude_from_sim no)
		(in_bom yes)
		(on_board yes)
		(dnp no)
		(property "Reference" "#PWR0201"
			(at 372.11 241.3 0)
			(effects
				(font
					(size 1.27 1.27)
				)
				(justify left bottom)
				(hide yes)
			)
		)
		(property "Value" "GND"
			(at 372.11 238.76 0)
			(effects
				(font
					(size 1.27 1.27)
					(thickness 0.15)
				)
			)
		)
		(property "Footprint" ""
			(at 381 242.57 0)
			(effects
				(font
					(size 1.27 1.27)
					(thickness 0.15)
				)
				(justify left bottom)
				(hide yes)
			)
		)
		(property "Datasheet" ""
			(at 381 247.65 0)
			(effects
				(font
					(size 1.27 1.27)
					(thickness 0.15)
				)
				(justify left bottom)
				(hide yes)
			)
		)
		(property "Description" ""
			(at 372.11 234.95 0)
			(effects
				(font
					(size 1.27 1.27)
				)
				(hide yes)
			)
		)
		(property "Author" "Antmicro"
			(at 381 242.57 0)
			(effects
				(font
					(size 1.27 1.27)
					(thickness 0.15)
				)
				(justify left bottom)
				(hide yes)
			)
		)
		(property "License" "Apache-2.0"
			(at 381 245.11 0)
			(effects
				(font
					(size 1.27 1.27)
					(thickness 0.15)
				)
				(justify left bottom)
				(hide yes)
			)
		)
		(pin "1"
		)
		(instances
			(project "jetson-orin-baseboard"
				(path ""
					(reference "#PWR0201")
					(unit 1)
				)
			)
		)
	)
	(symbol
		(lib_id "antmicropower:GND")
		(at 218.44 220.98 0)
		(unit 1)
		(exclude_from_sim no)
		(in_bom yes)
		(on_board yes)
		(dnp no)
		(property "Reference" "#PWR0361"
			(at 218.44 227.33 0)
			(effects
				(font
					(size 1.27 1.27)
				)
				(justify left bottom)
				(hide yes)
			)
		)
		(property "Value" "GND"
			(at 218.44 224.79 0)
			(effects
				(font
					(size 1.27 1.27)
					(thickness 0.15)
				)
			)
		)
		(property "Footprint" ""
			(at 227.33 228.6 0)
			(effects
				(font
					(size 1.27 1.27)
					(thickness 0.15)
				)
				(justify left bottom)
				(hide yes)
			)
		)
		(property "Datasheet" ""
			(at 227.33 233.68 0)
			(effects
				(font
					(size 1.27 1.27)
					(thickness 0.15)
				)
				(justify left bottom)
				(hide yes)
			)
		)
		(property "Description" ""
			(at 218.44 220.98 0)
			(effects
				(font
					(size 1.27 1.27)
				)
				(hide yes)
			)
		)
		(property "Author" "Antmicro"
			(at 227.33 228.6 0)
			(effects
				(font
					(size 1.27 1.27)
					(thickness 0.15)
				)
				(justify left bottom)
				(hide yes)
			)
		)
		(property "License" "Apache-2.0"
			(at 227.33 231.14 0)
			(effects
				(font
					(size 1.27 1.27)
					(thickness 0.15)
				)
				(justify left bottom)
				(hide yes)
			)
		)
		(pin "1"
		)
		(instances
			(project "jetson-orin-baseboard"
				(path ""
					(reference "#PWR0361")
					(unit 1)
				)
			)
		)
	)
	(symbol
		(lib_id "antmicropower:+3V3")
		(at 76.2 232.41 0)
		(unit 1)
		(exclude_from_sim no)
		(in_bom yes)
		(on_board yes)
		(dnp no)
		(property "Reference" "#PWR0220"
			(at 76.2 236.22 0)
			(effects
				(font
					(size 1.27 1.27)
				)
				(justify left bottom)
				(hide yes)
			)
		)
		(property "Value" "+3V3"
			(at 73.025 229.235 0)
			(effects
				(font
					(size 1.27 1.27)
					(thickness 0.15)
				)
				(justify left bottom)
			)
		)
		(property "Footprint" ""
			(at 91.44 240.03 0)
			(effects
				(font
					(size 1.27 1.27)
					(thickness 0.15)
				)
				(justify left bottom)
				(hide yes)
			)
		)
		(property "Datasheet" ""
			(at 91.44 242.57 0)
			(effects
				(font
					(size 1.27 1.27)
					(thickness 0.15)
				)
				(justify left bottom)
				(hide yes)
			)
		)
		(property "Description" ""
			(at 76.2 232.41 0)
			(effects
				(font
					(size 1.27 1.27)
				)
				(hide yes)
			)
		)
		(property "Author" "Antmicro"
			(at 91.44 234.95 0)
			(effects
				(font
					(size 1.27 1.27)
					(thickness 0.15)
				)
				(justify left bottom)
				(hide yes)
			)
		)
		(property "License" "Apache-2.0"
			(at 91.44 237.49 0)
			(effects
				(font
					(size 1.27 1.27)
					(thickness 0.15)
				)
				(justify left bottom)
				(hide yes)
			)
		)
		(pin "1"
		)
		(instances
			(project "jetson-orin-baseboard"
				(path ""
					(reference "#PWR0220")
					(unit 1)
				)
			)
		)
	)
	(symbol
		(lib_id "antmicroPMICPowerDistributionSwitchesLoadDrivers:AP22615A_TSOT26")
		(at 92.71 243.84 0)
		(unit 1)
		(exclude_from_sim no)
		(in_bom yes)
		(on_board yes)
		(dnp no)
		(property "Reference" "U25"
			(at 100.33 237.49 0)
			(effects
				(font
					(size 1.27 1.27)
				)
			)
		)
		(property "Value" "AP22615A_TSOT26"
			(at 123.19 248.92 0)
			(effects
				(font
					(size 1.27 1.27)
					(thickness 0.15)
				)
				(justify left bottom)
				(hide yes)
			)
		)
		(property "Footprint" "antmicro-footprints:TSOT23-6"
			(at 123.19 251.46 0)
			(effects
				(font
					(size 1.27 1.27)
					(thickness 0.15)
				)
				(justify left bottom)
				(hide yes)
			)
		)
		(property "Datasheet" "https://www.mouser.com/datasheet/2/115/DIOD_S_A0008958405_1-2543193.pdf"
			(at 123.19 254 0)
			(effects
				(font
					(size 1.27 1.27)
					(thickness 0.15)
				)
				(justify left bottom)
				(hide yes)
			)
		)
		(property "Description" ""
			(at 92.71 243.84 0)
			(effects
				(font
					(size 1.27 1.27)
				)
				(hide yes)
			)
		)
		(property "MPN" "AP22615AWU-7"
			(at 100.33 240.03 0)
			(effects
				(font
					(size 1.27 1.27)
					(thickness 0.15)
				)
			)
		)
		(property "Manufacturer" "Diodes Incorporated"
			(at 123.19 259.08 0)
			(effects
				(font
					(size 1.27 1.27)
					(thickness 0.15)
				)
				(justify left bottom)
				(hide yes)
			)
		)
		(property "Author" "Antmicro"
			(at 123.19 261.62 0)
			(effects
				(font
					(size 1.27 1.27)
					(thickness 0.15)
				)
				(justify left bottom)
				(hide yes)
			)
		)
		(property "License" "Apache-2.0"
			(at 123.19 264.16 0)
			(effects
				(font
					(size 1.27 1.27)
					(thickness 0.15)
				)
				(justify left bottom)
				(hide yes)
			)
		)
		(pin "1"
		)
		(pin "2"
		)
		(pin "3"
		)
		(pin "4"
		)
		(pin "5"
		)
		(pin "6"
		)
		(instances
			(project "jetson-orin-baseboard"
				(path ""
					(reference "U25")
					(unit 1)
				)
			)
		)
	)
	(symbol
		(lib_id "antmicropower:GND")
		(at 364.49 247.65 0)
		(unit 1)
		(exclude_from_sim no)
		(in_bom yes)
		(on_board yes)
		(dnp no)
		(property "Reference" "#PWR0182"
			(at 364.49 254 0)
			(effects
				(font
					(size 1.27 1.27)
				)
				(justify left bottom)
				(hide yes)
			)
		)
		(property "Value" "GND"
			(at 364.49 251.46 0)
			(effects
				(font
					(size 1.27 1.27)
					(thickness 0.15)
				)
			)
		)
		(property "Footprint" ""
			(at 373.38 255.27 0)
			(effects
				(font
					(size 1.27 1.27)
					(thickness 0.15)
				)
				(justify left bottom)
				(hide yes)
			)
		)
		(property "Datasheet" ""
			(at 373.38 260.35 0)
			(effects
				(font
					(size 1.27 1.27)
					(thickness 0.15)
				)
				(justify left bottom)
				(hide yes)
			)
		)
		(property "Description" ""
			(at 364.49 247.65 0)
			(effects
				(font
					(size 1.27 1.27)
				)
				(hide yes)
			)
		)
		(property "Author" "Antmicro"
			(at 373.38 255.27 0)
			(effects
				(font
					(size 1.27 1.27)
					(thickness 0.15)
				)
				(justify left bottom)
				(hide yes)
			)
		)
		(property "License" "Apache-2.0"
			(at 373.38 257.81 0)
			(effects
				(font
					(size 1.27 1.27)
					(thickness 0.15)
				)
				(justify left bottom)
				(hide yes)
			)
		)
		(pin "1"
		)
		(instances
			(project "jetson-orin-baseboard"
				(path ""
					(reference "#PWR0182")
					(unit 1)
				)
			)
		)
	)
	(symbol
		(lib_id "antmicroResistorNetworksArrays:R_4x0R_0201_array")
		(at 157.48 46.99 0)
		(mirror x)
		(unit 1)
		(exclude_from_sim no)
		(in_bom yes)
		(on_board yes)
		(dnp no)
		(property "Reference" "R107"
			(at 162.56 33.655 0)
			(effects
				(font
					(size 1.27 1.27)
				)
			)
		)
		(property "Value" "R_4x0R_0201_array"
			(at 184.15 39.37 0)
			(effects
				(font
					(size 1.27 1.27)
					(thickness 0.15)
				)
				(justify left bottom)
				(hide yes)
			)
		)
		(property "Footprint" "antmicro-footprints:R_Array_4x0201_Panasonic_EXB18V"
			(at 184.15 34.29 0)
			(effects
				(font
					(size 1.27 1.27)
					(thickness 0.15)
				)
				(justify left bottom)
				(hide yes)
			)
		)
		(property "Datasheet" "http://industrial.panasonic.com/cdbs/www-data/pdf/AOC0000/AOC0000C14.pdf"
			(at 184.15 31.75 0)
			(effects
				(font
					(size 1.27 1.27)
					(thickness 0.15)
				)
				(justify left bottom)
				(hide yes)
			)
		)
		(property "Description" ""
			(at 157.48 46.99 0)
			(effects
				(font
					(size 1.27 1.27)
				)
				(hide yes)
			)
		)
		(property "MPN" "EXB-18VR000X"
			(at 184.15 29.21 0)
			(effects
				(font
					(size 1.27 1.27)
					(thickness 0.15)
				)
				(justify left bottom)
				(hide yes)
			)
		)
		(property "Manufacturer" "Panasonic"
			(at 184.15 26.67 0)
			(effects
				(font
					(size 1.27 1.27)
					(thickness 0.15)
				)
				(justify left bottom)
				(hide yes)
			)
		)
		(property "Val" "4x0R_0201"
			(at 162.56 36.195 0)
			(effects
				(font
					(size 1.27 1.27)
					(thickness 0.15)
				)
			)
		)
		(property "Author" "Antmicro"
			(at 184.15 24.13 0)
			(effects
				(font
					(size 1.27 1.27)
					(thickness 0.15)
				)
				(justify left bottom)
				(hide yes)
			)
		)
		(property "License" "Apache-2.0"
			(at 184.15 21.59 0)
			(effects
				(font
					(size 1.27 1.27)
					(thickness 0.15)
				)
				(justify left bottom)
				(hide yes)
			)
		)
		(pin "1"
		)
		(pin "2"
		)
		(pin "3"
		)
		(pin "4"
		)
		(pin "5"
		)
		(pin "6"
		)
		(pin "7"
		)
		(pin "8"
		)
		(instances
			(project "jetson-orin-baseboard"
				(path ""
					(reference "R107")
					(unit 1)
				)
			)
		)
	)
	(symbol
		(lib_id "antmicroCapacitors0402:C_100n_0402")
		(at 334.01 203.2 270)
		(mirror x)
		(unit 1)
		(exclude_from_sim no)
		(in_bom yes)
		(on_board yes)
		(dnp no)
		(property "Reference" "C96"
			(at 332.105 199.39 90)
			(effects
				(font
					(size 1.27 1.27)
				)
				(justify right)
			)
		)
		(property "Value" "C_100n_0402"
			(at 323.85 182.88 0)
			(effects
				(font
					(size 1.27 1.27)
					(thickness 0.15)
				)
				(justify left bottom)
				(hide yes)
			)
		)
		(property "Footprint" "antmicro-footprints:C_0402_1005Metric"
			(at 321.31 182.88 0)
			(effects
				(font
					(size 1.27 1.27)
					(thickness 0.15)
				)
				(justify left bottom)
				(hide yes)
			)
		)
		(property "Datasheet" "https://www.murata.com/products/productdetail?partno=GRM155R61H104KE14%23"
			(at 318.77 182.88 0)
			(effects
				(font
					(size 1.27 1.27)
					(thickness 0.15)
				)
				(justify left bottom)
				(hide yes)
			)
		)
		(property "Description" ""
			(at 334.01 203.2 0)
			(effects
				(font
					(size 1.27 1.27)
				)
				(hide yes)
			)
		)
		(property "Manufacturer" "Murata"
			(at 313.69 182.88 0)
			(effects
				(font
					(size 1.27 1.27)
					(thickness 0.15)
				)
				(justify left bottom)
				(hide yes)
			)
		)
		(property "MPN" "GRM155R61H104KE14D"
			(at 316.23 182.88 0)
			(effects
				(font
					(size 1.27 1.27)
					(thickness 0.15)
				)
				(justify left bottom)
				(hide yes)
			)
		)
		(property "Val" "100n"
			(at 332.105 201.93 90)
			(effects
				(font
					(size 1.27 1.27)
					(thickness 0.15)
				)
				(justify right)
			)
		)
		(property "License" "Apache-2.0"
			(at 311.15 182.88 0)
			(effects
				(font
					(size 1.27 1.27)
					(thickness 0.15)
				)
				(justify left bottom)
				(hide yes)
			)
		)
		(property "Author" "Antmicro"
			(at 308.61 182.88 0)
			(effects
				(font
					(size 1.27 1.27)
					(thickness 0.15)
				)
				(justify left bottom)
				(hide yes)
			)
		)
		(property "Voltage" "50V"
			(at 306.07 182.88 0)
			(effects
				(font
					(size 1.27 1.27)
				)
				(justify left bottom)
				(hide yes)
			)
		)
		(property "Dielectric" "X5R"
			(at 303.53 182.88 0)
			(effects
				(font
					(size 1.27 1.27)
				)
				(justify left bottom)
				(hide yes)
			)
		)
		(pin "1"
		)
		(pin "2"
		)
		(instances
			(project "jetson-orin-baseboard"
				(path ""
					(reference "C96")
					(unit 1)
				)
			)
		)
	)
	(symbol
		(lib_id "antmicroCapacitors0402:C_100n_0402")
		(at 372.11 233.68 270)
		(mirror x)
		(unit 1)
		(exclude_from_sim no)
		(in_bom yes)
		(on_board yes)
		(dnp no)
		(property "Reference" "C101"
			(at 374.015 229.87 90)
			(effects
				(font
					(size 1.27 1.27)
				)
				(justify left)
			)
		)
		(property "Value" "C_100n_0402"
			(at 361.95 213.36 0)
			(effects
				(font
					(size 1.27 1.27)
					(thickness 0.15)
				)
				(justify left bottom)
				(hide yes)
			)
		)
		(property "Footprint" "antmicro-footprints:C_0402_1005Metric"
			(at 359.41 213.36 0)
			(effects
				(font
					(size 1.27 1.27)
					(thickness 0.15)
				)
				(justify left bottom)
				(hide yes)
			)
		)
		(property "Datasheet" "https://www.murata.com/products/productdetail?partno=GRM155R61H104KE14%23"
			(at 356.87 213.36 0)
			(effects
				(font
					(size 1.27 1.27)
					(thickness 0.15)
				)
				(justify left bottom)
				(hide yes)
			)
		)
		(property "Description" ""
			(at 372.11 233.68 0)
			(effects
				(font
					(size 1.27 1.27)
				)
				(hide yes)
			)
		)
		(property "Manufacturer" "Murata"
			(at 351.79 213.36 0)
			(effects
				(font
					(size 1.27 1.27)
					(thickness 0.15)
				)
				(justify left bottom)
				(hide yes)
			)
		)
		(property "MPN" "GRM155R61H104KE14D"
			(at 354.33 213.36 0)
			(effects
				(font
					(size 1.27 1.27)
					(thickness 0.15)
				)
				(justify left bottom)
				(hide yes)
			)
		)
		(property "Val" "100n"
			(at 374.015 232.41 90)
			(effects
				(font
					(size 1.27 1.27)
					(thickness 0.15)
				)
				(justify left)
			)
		)
		(property "License" "Apache-2.0"
			(at 349.25 213.36 0)
			(effects
				(font
					(size 1.27 1.27)
					(thickness 0.15)
				)
				(justify left bottom)
				(hide yes)
			)
		)
		(property "Author" "Antmicro"
			(at 346.71 213.36 0)
			(effects
				(font
					(size 1.27 1.27)
					(thickness 0.15)
				)
				(justify left bottom)
				(hide yes)
			)
		)
		(property "Voltage" "50V"
			(at 344.17 213.36 0)
			(effects
				(font
					(size 1.27 1.27)
				)
				(justify left bottom)
				(hide yes)
			)
		)
		(property "Dielectric" "X5R"
			(at 341.63 213.36 0)
			(effects
				(font
					(size 1.27 1.27)
				)
				(justify left bottom)
				(hide yes)
			)
		)
		(pin "1"
		)
		(pin "2"
		)
		(instances
			(project "jetson-orin-baseboard"
				(path ""
					(reference "C101")
					(unit 1)
				)
			)
		)
	)
	(symbol
		(lib_id "antmicropower:GND")
		(at 123.19 254 0)
		(unit 1)
		(exclude_from_sim no)
		(in_bom yes)
		(on_board yes)
		(dnp no)
		(property "Reference" "#PWR0199"
			(at 123.19 260.35 0)
			(effects
				(font
					(size 1.27 1.27)
				)
				(justify left bottom)
				(hide yes)
			)
		)
		(property "Value" "GND"
			(at 123.19 257.81 0)
			(effects
				(font
					(size 1.27 1.27)
					(thickness 0.15)
				)
			)
		)
		(property "Footprint" ""
			(at 132.08 261.62 0)
			(effects
				(font
					(size 1.27 1.27)
					(thickness 0.15)
				)
				(justify left bottom)
				(hide yes)
			)
		)
		(property "Datasheet" ""
			(at 132.08 266.7 0)
			(effects
				(font
					(size 1.27 1.27)
					(thickness 0.15)
				)
				(justify left bottom)
				(hide yes)
			)
		)
		(property "Description" ""
			(at 123.19 254 0)
			(effects
				(font
					(size 1.27 1.27)
				)
				(hide yes)
			)
		)
		(property "Author" "Antmicro"
			(at 132.08 261.62 0)
			(effects
				(font
					(size 1.27 1.27)
					(thickness 0.15)
				)
				(justify left bottom)
				(hide yes)
			)
		)
		(property "License" "Apache-2.0"
			(at 132.08 264.16 0)
			(effects
				(font
					(size 1.27 1.27)
					(thickness 0.15)
				)
				(justify left bottom)
				(hide yes)
			)
		)
		(pin "1"
		)
		(instances
			(project "jetson-orin-baseboard"
				(path ""
					(reference "#PWR0199")
					(unit 1)
				)
			)
		)
	)
	(symbol
		(lib_id "antmicroCapacitors0402:C_100n_0402")
		(at 76.2 234.95 90)
		(mirror x)
		(unit 1)
		(exclude_from_sim no)
		(in_bom yes)
		(on_board yes)
		(dnp no)
		(property "Reference" "C43"
			(at 78.105 236.22 90)
			(effects
				(font
					(size 1.27 1.27)
				)
				(justify right)
			)
		)
		(property "Value" "C_100n_0402"
			(at 86.36 255.27 0)
			(effects
				(font
					(size 1.27 1.27)
					(thickness 0.15)
				)
				(justify left bottom)
				(hide yes)
			)
		)
		(property "Footprint" "antmicro-footprints:C_0402_1005Metric"
			(at 88.9 255.27 0)
			(effects
				(font
					(size 1.27 1.27)
					(thickness 0.15)
				)
				(justify left bottom)
				(hide yes)
			)
		)
		(property "Datasheet" "https://www.murata.com/products/productdetail?partno=GRM155R61H104KE14%23"
			(at 91.44 255.27 0)
			(effects
				(font
					(size 1.27 1.27)
					(thickness 0.15)
				)
				(justify left bottom)
				(hide yes)
			)
		)
		(property "Description" ""
			(at 76.2 234.95 0)
			(effects
				(font
					(size 1.27 1.27)
				)
				(hide yes)
			)
		)
		(property "Manufacturer" "Murata"
			(at 96.52 255.27 0)
			(effects
				(font
					(size 1.27 1.27)
					(thickness 0.15)
				)
				(justify left bottom)
				(hide yes)
			)
		)
		(property "MPN" "GRM155R61H104KE14D"
			(at 93.98 255.27 0)
			(effects
				(font
					(size 1.27 1.27)
					(thickness 0.15)
				)
				(justify left bottom)
				(hide yes)
			)
		)
		(property "Val" "100n"
			(at 78.105 238.76 90)
			(effects
				(font
					(size 1.27 1.27)
					(thickness 0.15)
				)
				(justify right)
			)
		)
		(property "License" "Apache-2.0"
			(at 99.06 255.27 0)
			(effects
				(font
					(size 1.27 1.27)
					(thickness 0.15)
				)
				(justify left bottom)
				(hide yes)
			)
		)
		(property "Author" "Antmicro"
			(at 101.6 255.27 0)
			(effects
				(font
					(size 1.27 1.27)
					(thickness 0.15)
				)
				(justify left bottom)
				(hide yes)
			)
		)
		(property "Voltage" "50V"
			(at 104.14 255.27 0)
			(effects
				(font
					(size 1.27 1.27)
				)
				(justify left bottom)
				(hide yes)
			)
		)
		(property "Dielectric" "X5R"
			(at 106.68 255.27 0)
			(effects
				(font
					(size 1.27 1.27)
				)
				(justify left bottom)
				(hide yes)
			)
		)
		(pin "1"
		)
		(pin "2"
		)
		(instances
			(project "jetson-orin-baseboard"
				(path ""
					(reference "C43")
					(unit 1)
				)
			)
		)
	)
	(symbol
		(lib_id "antmicroResistors0402:R_0R_0402")
		(at 72.39 135.89 90)
		(unit 1)
		(exclude_from_sim no)
		(in_bom no)
		(on_board yes)
		(dnp yes)
		(property "Reference" "R179"
			(at 73.66 132.08 90)
			(effects
				(font
					(size 1.27 1.27)
				)
				(justify right)
			)
		)
		(property "Value" "R_0R_0402"
			(at 85.09 115.57 0)
			(effects
				(font
					(size 1.27 1.27)
					(thickness 0.15)
				)
				(justify left bottom)
				(hide yes)
			)
		)
		(property "Footprint" "antmicro-footprints:R_0402_1005Metric"
			(at 87.63 115.57 0)
			(effects
				(font
					(size 1.27 1.27)
					(thickness 0.15)
				)
				(justify left bottom)
				(hide yes)
			)
		)
		(property "Datasheet" "https://industrial.panasonic.com/cdbs/www-data/pdf/RDA0000/AOA0000C301.pdf"
			(at 90.17 115.57 0)
			(effects
				(font
					(size 1.27 1.27)
					(thickness 0.15)
				)
				(justify left bottom)
				(hide yes)
			)
		)
		(property "Description" ""
			(at 72.39 135.89 0)
			(effects
				(font
					(size 1.27 1.27)
				)
				(hide yes)
			)
		)
		(property "Manufacturer" "Panasonic"
			(at 95.25 115.57 0)
			(effects
				(font
					(size 1.27 1.27)
					(thickness 0.15)
				)
				(justify left bottom)
				(hide yes)
			)
		)
		(property "MPN" "ERJ2GE0R00X"
			(at 92.71 115.57 0)
			(effects
				(font
					(size 1.27 1.27)
					(thickness 0.15)
				)
				(justify left bottom)
				(hide yes)
			)
		)
		(property "Val" "0R"
			(at 73.66 134.62 90)
			(effects
				(font
					(size 1.27 1.27)
					(thickness 0.15)
				)
				(justify right)
			)
		)
		(property "License" "Apache-2.0"
			(at 97.79 115.57 0)
			(effects
				(font
					(size 1.27 1.27)
					(thickness 0.15)
				)
				(justify left bottom)
				(hide yes)
			)
		)
		(property "Author" "Antmicro"
			(at 100.33 115.57 0)
			(effects
				(font
					(size 1.27 1.27)
					(thickness 0.15)
				)
				(justify left bottom)
				(hide yes)
			)
		)
		(property "Tolerance" "~"
			(at 82.55 115.57 0)
			(effects
				(font
					(size 1.27 1.27)
				)
				(justify left bottom)
				(hide yes)
			)
		)
		(property "Current" "1A"
			(at 102.87 115.57 0)
			(effects
				(font
					(size 1.27 1.27)
					(thickness 0.15)
				)
				(justify left bottom)
				(hide yes)
			)
		)
		(pin "1"
		)
		(pin "2"
		)
		(instances
			(project "jetson-orin-baseboard"
				(path ""
					(reference "R179")
					(unit 1)
				)
			)
		)
	)
	(symbol
		(lib_id "antmicropower:GND")
		(at 349.25 162.56 0)
		(unit 1)
		(exclude_from_sim no)
		(in_bom yes)
		(on_board yes)
		(dnp no)
		(property "Reference" "#PWR0354"
			(at 349.25 168.91 0)
			(effects
				(font
					(size 1.27 1.27)
				)
				(justify left bottom)
				(hide yes)
			)
		)
		(property "Value" "GND"
			(at 349.25 166.37 0)
			(effects
				(font
					(size 1.27 1.27)
					(thickness 0.15)
				)
			)
		)
		(property "Footprint" ""
			(at 358.14 170.18 0)
			(effects
				(font
					(size 1.27 1.27)
					(thickness 0.15)
				)
				(justify left bottom)
				(hide yes)
			)
		)
		(property "Datasheet" ""
			(at 358.14 175.26 0)
			(effects
				(font
					(size 1.27 1.27)
					(thickness 0.15)
				)
				(justify left bottom)
				(hide yes)
			)
		)
		(property "Description" ""
			(at 349.25 162.56 0)
			(effects
				(font
					(size 1.27 1.27)
				)
				(hide yes)
			)
		)
		(property "Author" "Antmicro"
			(at 358.14 170.18 0)
			(effects
				(font
					(size 1.27 1.27)
					(thickness 0.15)
				)
				(justify left bottom)
				(hide yes)
			)
		)
		(property "License" "Apache-2.0"
			(at 358.14 172.72 0)
			(effects
				(font
					(size 1.27 1.27)
					(thickness 0.15)
				)
				(justify left bottom)
				(hide yes)
			)
		)
		(pin "1"
		)
		(instances
			(project "jetson-orin-baseboard"
				(path ""
					(reference "#PWR0354")
					(unit 1)
				)
			)
		)
	)
	(symbol
		(lib_id "antmicropower:+1V8")
		(at 35.56 129.54 0)
		(unit 1)
		(exclude_from_sim no)
		(in_bom yes)
		(on_board yes)
		(dnp no)
		(property "Reference" "#PWR0159"
			(at 35.56 133.35 0)
			(effects
				(font
					(size 1.27 1.27)
				)
				(justify left bottom)
				(hide yes)
			)
		)
		(property "Value" "+1V8"
			(at 34.925 125.73 0)
			(effects
				(font
					(size 1.27 1.27)
					(thickness 0.15)
				)
			)
		)
		(property "Footprint" ""
			(at 50.8 137.16 0)
			(effects
				(font
					(size 1.27 1.27)
					(thickness 0.15)
				)
				(justify left bottom)
				(hide yes)
			)
		)
		(property "Datasheet" ""
			(at 50.8 139.7 0)
			(effects
				(font
					(size 1.27 1.27)
					(thickness 0.15)
				)
				(justify left bottom)
				(hide yes)
			)
		)
		(property "Description" ""
			(at 35.56 129.54 0)
			(effects
				(font
					(size 1.27 1.27)
				)
				(hide yes)
			)
		)
		(property "Author" "Antmicro"
			(at 50.8 134.62 0)
			(effects
				(font
					(size 1.27 1.27)
					(thickness 0.15)
				)
				(justify left bottom)
				(hide yes)
			)
		)
		(property "License" "Apache-2.0"
			(at 50.8 137.16 0)
			(effects
				(font
					(size 1.27 1.27)
					(thickness 0.15)
				)
				(justify left bottom)
				(hide yes)
			)
		)
		(pin "1"
		)
		(instances
			(project "jetson-orin-baseboard"
				(path ""
					(reference "#PWR0159")
					(unit 1)
				)
			)
		)
	)
	(symbol
		(lib_id "antmicroResistors0402:R_10k_0402")
		(at 86.36 203.2 270)
		(unit 1)
		(exclude_from_sim no)
		(in_bom yes)
		(on_board yes)
		(dnp no)
		(property "Reference" "R66"
			(at 87.63 204.47 90)
			(effects
				(font
					(size 1.27 1.27)
				)
				(justify left)
			)
		)
		(property "Value" "R_10k_0402"
			(at 73.66 223.52 0)
			(effects
				(font
					(size 1.27 1.27)
					(thickness 0.15)
				)
				(justify left bottom)
				(hide yes)
			)
		)
		(property "Footprint" "antmicro-footprints:R_0402_1005Metric"
			(at 71.12 223.52 0)
			(effects
				(font
					(size 1.27 1.27)
					(thickness 0.15)
				)
				(justify left bottom)
				(hide yes)
			)
		)
		(property "Datasheet" "https://www.bourns.com/docs/product-datasheets/cr.pdf"
			(at 68.58 223.52 0)
			(effects
				(font
					(size 1.27 1.27)
					(thickness 0.15)
				)
				(justify left bottom)
				(hide yes)
			)
		)
		(property "Description" ""
			(at 86.36 203.2 0)
			(effects
				(font
					(size 1.27 1.27)
				)
				(hide yes)
			)
		)
		(property "Manufacturer" "Bourns"
			(at 63.5 223.52 0)
			(effects
				(font
					(size 1.27 1.27)
					(thickness 0.15)
				)
				(justify left bottom)
				(hide yes)
			)
		)
		(property "MPN" "CR0402-FX-1002GLF"
			(at 66.04 223.52 0)
			(effects
				(font
					(size 1.27 1.27)
					(thickness 0.15)
				)
				(justify left bottom)
				(hide yes)
			)
		)
		(property "Val" "10k"
			(at 87.63 207.01 90)
			(effects
				(font
					(size 1.27 1.27)
					(thickness 0.15)
				)
				(justify left)
			)
		)
		(property "License" "Apache-2.0"
			(at 60.96 223.52 0)
			(effects
				(font
					(size 1.27 1.27)
					(thickness 0.15)
				)
				(justify left bottom)
				(hide yes)
			)
		)
		(property "Author" "Antmicro"
			(at 58.42 223.52 0)
			(effects
				(font
					(size 1.27 1.27)
					(thickness 0.15)
				)
				(justify left bottom)
				(hide yes)
			)
		)
		(property "Tolerance" "1%"
			(at 76.2 223.52 0)
			(effects
				(font
					(size 1.27 1.27)
				)
				(justify left bottom)
				(hide yes)
			)
		)
		(pin "1"
		)
		(pin "2"
		)
		(instances
			(project "jetson-orin-baseboard"
				(path ""
					(reference "R66")
					(unit 1)
				)
			)
		)
	)
	(symbol
		(lib_id "antmicropower:+3V3")
		(at 86.36 200.66 0)
		(unit 1)
		(exclude_from_sim no)
		(in_bom yes)
		(on_board yes)
		(dnp no)
		(property "Reference" "#PWR0356"
			(at 86.36 204.47 0)
			(effects
				(font
					(size 1.27 1.27)
				)
				(justify left bottom)
				(hide yes)
			)
		)
		(property "Value" "+3V3"
			(at 83.185 196.85 0)
			(effects
				(font
					(size 1.27 1.27)
					(thickness 0.15)
				)
				(justify left)
			)
		)
		(property "Footprint" ""
			(at 101.6 208.28 0)
			(effects
				(font
					(size 1.27 1.27)
					(thickness 0.15)
				)
				(justify left bottom)
				(hide yes)
			)
		)
		(property "Datasheet" ""
			(at 101.6 210.82 0)
			(effects
				(font
					(size 1.27 1.27)
					(thickness 0.15)
				)
				(justify left bottom)
				(hide yes)
			)
		)
		(property "Description" ""
			(at 86.36 200.66 0)
			(effects
				(font
					(size 1.27 1.27)
				)
				(hide yes)
			)
		)
		(property "Author" "Antmicro"
			(at 101.6 203.2 0)
			(effects
				(font
					(size 1.27 1.27)
					(thickness 0.15)
				)
				(justify left bottom)
				(hide yes)
			)
		)
		(property "License" "Apache-2.0"
			(at 101.6 205.74 0)
			(effects
				(font
					(size 1.27 1.27)
					(thickness 0.15)
				)
				(justify left bottom)
				(hide yes)
			)
		)
		(pin "1"
		)
		(instances
			(project "jetson-orin-baseboard"
				(path ""
					(reference "#PWR0356")
					(unit 1)
				)
			)
		)
	)
	(symbol
		(lib_id "antmicropower:GND")
		(at 344.17 162.56 0)
		(unit 1)
		(exclude_from_sim no)
		(in_bom yes)
		(on_board yes)
		(dnp no)
		(property "Reference" "#PWR0353"
			(at 344.17 168.91 0)
			(effects
				(font
					(size 1.27 1.27)
				)
				(justify left bottom)
				(hide yes)
			)
		)
		(property "Value" "GND"
			(at 344.17 166.37 0)
			(effects
				(font
					(size 1.27 1.27)
					(thickness 0.15)
				)
			)
		)
		(property "Footprint" ""
			(at 353.06 170.18 0)
			(effects
				(font
					(size 1.27 1.27)
					(thickness 0.15)
				)
				(justify left bottom)
				(hide yes)
			)
		)
		(property "Datasheet" ""
			(at 353.06 175.26 0)
			(effects
				(font
					(size 1.27 1.27)
					(thickness 0.15)
				)
				(justify left bottom)
				(hide yes)
			)
		)
		(property "Description" ""
			(at 344.17 162.56 0)
			(effects
				(font
					(size 1.27 1.27)
				)
				(hide yes)
			)
		)
		(property "Author" "Antmicro"
			(at 353.06 170.18 0)
			(effects
				(font
					(size 1.27 1.27)
					(thickness 0.15)
				)
				(justify left bottom)
				(hide yes)
			)
		)
		(property "License" "Apache-2.0"
			(at 353.06 172.72 0)
			(effects
				(font
					(size 1.27 1.27)
					(thickness 0.15)
				)
				(justify left bottom)
				(hide yes)
			)
		)
		(pin "1"
		)
		(instances
			(project "jetson-orin-baseboard"
				(path ""
					(reference "#PWR0353")
					(unit 1)
				)
			)
		)
	)
	(symbol
		(lib_id "antmicroResistorNetworksArrays:R_4x0R_0201_array")
		(at 157.48 101.6 0)
		(mirror x)
		(unit 1)
		(exclude_from_sim no)
		(in_bom no)
		(on_board yes)
		(dnp yes)
		(property "Reference" "R122"
			(at 162.56 88.265 0)
			(effects
				(font
					(size 1.27 1.27)
				)
			)
		)
		(property "Value" "R_4x0R_0201_array"
			(at 184.15 93.98 0)
			(effects
				(font
					(size 1.27 1.27)
					(thickness 0.15)
				)
				(justify left bottom)
				(hide yes)
			)
		)
		(property "Footprint" "antmicro-footprints:R_Array_4x0201_Panasonic_EXB18V"
			(at 184.15 88.9 0)
			(effects
				(font
					(size 1.27 1.27)
					(thickness 0.15)
				)
				(justify left bottom)
				(hide yes)
			)
		)
		(property "Datasheet" "http://industrial.panasonic.com/cdbs/www-data/pdf/AOC0000/AOC0000C14.pdf"
			(at 184.15 86.36 0)
			(effects
				(font
					(size 1.27 1.27)
					(thickness 0.15)
				)
				(justify left bottom)
				(hide yes)
			)
		)
		(property "Description" ""
			(at 157.48 101.6 0)
			(effects
				(font
					(size 1.27 1.27)
				)
				(hide yes)
			)
		)
		(property "MPN" "EXB-18VR000X"
			(at 184.15 83.82 0)
			(effects
				(font
					(size 1.27 1.27)
					(thickness 0.15)
				)
				(justify left bottom)
				(hide yes)
			)
		)
		(property "Manufacturer" "Panasonic"
			(at 184.15 81.28 0)
			(effects
				(font
					(size 1.27 1.27)
					(thickness 0.15)
				)
				(justify left bottom)
				(hide yes)
			)
		)
		(property "Val" "4x0R_0201"
			(at 162.56 90.805 0)
			(effects
				(font
					(size 1.27 1.27)
					(thickness 0.15)
				)
			)
		)
		(property "Author" "Antmicro"
			(at 184.15 78.74 0)
			(effects
				(font
					(size 1.27 1.27)
					(thickness 0.15)
				)
				(justify left bottom)
				(hide yes)
			)
		)
		(property "License" "Apache-2.0"
			(at 184.15 76.2 0)
			(effects
				(font
					(size 1.27 1.27)
					(thickness 0.15)
				)
				(justify left bottom)
				(hide yes)
			)
		)
		(pin "1"
		)
		(pin "2"
		)
		(pin "3"
		)
		(pin "4"
		)
		(pin "5"
		)
		(pin "6"
		)
		(pin "7"
		)
		(pin "8"
		)
		(instances
			(project "jetson-orin-baseboard"
				(path ""
					(reference "R122")
					(unit 1)
				)
			)
		)
	)
	(symbol
		(lib_id "antmicroCapacitors0402:C_1u_0402")
		(at 349.25 161.29 90)
		(unit 1)
		(exclude_from_sim no)
		(in_bom yes)
		(on_board yes)
		(dnp no)
		(fields_autoplaced yes)
		(property "Reference" "C99"
			(at 351.79 157.4736 90)
			(effects
				(font
					(size 1.27 1.27)
				)
				(justify right)
			)
		)
		(property "Value" "C_1u_0402"
			(at 359.41 140.97 0)
			(effects
				(font
					(size 1.27 1.27)
					(thickness 0.15)
				)
				(justify left bottom)
				(hide yes)
			)
		)
		(property "Footprint" "antmicro-footprints:C_0402_1005Metric"
			(at 361.95 140.97 0)
			(effects
				(font
					(size 1.27 1.27)
					(thickness 0.15)
				)
				(justify left bottom)
				(hide yes)
			)
		)
		(property "Datasheet" "https://product.tdk.com/en/search/capacitor/ceramic/mlcc/info?part_no=C1005X6S1A105K050BC"
			(at 364.49 140.97 0)
			(effects
				(font
					(size 1.27 1.27)
					(thickness 0.15)
				)
				(justify left bottom)
				(hide yes)
			)
		)
		(property "Description" ""
			(at 349.25 161.29 0)
			(effects
				(font
					(size 1.27 1.27)
				)
				(hide yes)
			)
		)
		(property "Manufacturer" "TDK"
			(at 369.57 140.97 0)
			(effects
				(font
					(size 1.27 1.27)
					(thickness 0.15)
				)
				(justify left bottom)
				(hide yes)
			)
		)
		(property "MPN" "C1005X6S1A105K050BC"
			(at 367.03 140.97 0)
			(effects
				(font
					(size 1.27 1.27)
					(thickness 0.15)
				)
				(justify left bottom)
				(hide yes)
			)
		)
		(property "Val" "1u"
			(at 351.79 160.0136 90)
			(effects
				(font
					(size 1.27 1.27)
					(thickness 0.15)
				)
				(justify right)
			)
		)
		(property "License" "Apache-2.0"
			(at 372.11 140.97 0)
			(effects
				(font
					(size 1.27 1.27)
					(thickness 0.15)
				)
				(justify left bottom)
				(hide yes)
			)
		)
		(property "Author" "Antmicro"
			(at 374.65 140.97 0)
			(effects
				(font
					(size 1.27 1.27)
					(thickness 0.15)
				)
				(justify left bottom)
				(hide yes)
			)
		)
		(property "Voltage" ""
			(at 377.19 140.97 0)
			(effects
				(font
					(size 1.27 1.27)
				)
				(justify left bottom)
				(hide yes)
			)
		)
		(property "Dielectric" ""
			(at 379.73 140.97 0)
			(effects
				(font
					(size 1.27 1.27)
				)
				(justify left bottom)
				(hide yes)
			)
		)
		(pin "1"
		)
		(pin "2"
		)
		(instances
			(project "jetson-orin-baseboard"
				(path ""
					(reference "C99")
					(unit 1)
				)
			)
		)
	)
	(symbol
		(lib_id "antmicroCapacitors0402:C_100n_0402")
		(at 372.11 203.2 270)
		(mirror x)
		(unit 1)
		(exclude_from_sim no)
		(in_bom yes)
		(on_board yes)
		(dnp no)
		(property "Reference" "C100"
			(at 374.015 199.39 90)
			(effects
				(font
					(size 1.27 1.27)
				)
				(justify left)
			)
		)
		(property "Value" "C_100n_0402"
			(at 361.95 182.88 0)
			(effects
				(font
					(size 1.27 1.27)
					(thickness 0.15)
				)
				(justify left bottom)
				(hide yes)
			)
		)
		(property "Footprint" "antmicro-footprints:C_0402_1005Metric"
			(at 359.41 182.88 0)
			(effects
				(font
					(size 1.27 1.27)
					(thickness 0.15)
				)
				(justify left bottom)
				(hide yes)
			)
		)
		(property "Datasheet" "https://www.murata.com/products/productdetail?partno=GRM155R61H104KE14%23"
			(at 356.87 182.88 0)
			(effects
				(font
					(size 1.27 1.27)
					(thickness 0.15)
				)
				(justify left bottom)
				(hide yes)
			)
		)
		(property "Description" ""
			(at 372.11 203.2 0)
			(effects
				(font
					(size 1.27 1.27)
				)
				(hide yes)
			)
		)
		(property "Manufacturer" "Murata"
			(at 351.79 182.88 0)
			(effects
				(font
					(size 1.27 1.27)
					(thickness 0.15)
				)
				(justify left bottom)
				(hide yes)
			)
		)
		(property "MPN" "GRM155R61H104KE14D"
			(at 354.33 182.88 0)
			(effects
				(font
					(size 1.27 1.27)
					(thickness 0.15)
				)
				(justify left bottom)
				(hide yes)
			)
		)
		(property "Val" "100n"
			(at 374.015 201.93 90)
			(effects
				(font
					(size 1.27 1.27)
					(thickness 0.15)
				)
				(justify left)
			)
		)
		(property "License" "Apache-2.0"
			(at 349.25 182.88 0)
			(effects
				(font
					(size 1.27 1.27)
					(thickness 0.15)
				)
				(justify left bottom)
				(hide yes)
			)
		)
		(property "Author" "Antmicro"
			(at 346.71 182.88 0)
			(effects
				(font
					(size 1.27 1.27)
					(thickness 0.15)
				)
				(justify left bottom)
				(hide yes)
			)
		)
		(property "Voltage" "50V"
			(at 344.17 182.88 0)
			(effects
				(font
					(size 1.27 1.27)
				)
				(justify left bottom)
				(hide yes)
			)
		)
		(property "Dielectric" "X5R"
			(at 341.63 182.88 0)
			(effects
				(font
					(size 1.27 1.27)
				)
				(justify left bottom)
				(hide yes)
			)
		)
		(pin "1"
		)
		(pin "2"
		)
		(instances
			(project "jetson-orin-baseboard"
				(path ""
					(reference "C100")
					(unit 1)
				)
			)
		)
	)
	(symbol
		(lib_id "antmicropower:+3V3")
		(at 195.58 200.66 0)
		(unit 1)
		(exclude_from_sim no)
		(in_bom yes)
		(on_board yes)
		(dnp no)
		(property "Reference" "#PWR0357"
			(at 195.58 204.47 0)
			(effects
				(font
					(size 1.27 1.27)
				)
				(justify left bottom)
				(hide yes)
			)
		)
		(property "Value" "+3V3"
			(at 192.405 196.85 0)
			(effects
				(font
					(size 1.27 1.27)
					(thickness 0.15)
				)
				(justify left)
			)
		)
		(property "Footprint" ""
			(at 210.82 208.28 0)
			(effects
				(font
					(size 1.27 1.27)
					(thickness 0.15)
				)
				(justify left bottom)
				(hide yes)
			)
		)
		(property "Datasheet" ""
			(at 210.82 210.82 0)
			(effects
				(font
					(size 1.27 1.27)
					(thickness 0.15)
				)
				(justify left bottom)
				(hide yes)
			)
		)
		(property "Description" ""
			(at 195.58 200.66 0)
			(effects
				(font
					(size 1.27 1.27)
				)
				(hide yes)
			)
		)
		(property "Author" "Antmicro"
			(at 210.82 203.2 0)
			(effects
				(font
					(size 1.27 1.27)
					(thickness 0.15)
				)
				(justify left bottom)
				(hide yes)
			)
		)
		(property "License" "Apache-2.0"
			(at 210.82 205.74 0)
			(effects
				(font
					(size 1.27 1.27)
					(thickness 0.15)
				)
				(justify left bottom)
				(hide yes)
			)
		)
		(pin "1"
		)
		(instances
			(project "jetson-orin-baseboard"
				(path ""
					(reference "#PWR0357")
					(unit 1)
				)
			)
		)
	)
	(symbol
		(lib_id "antmicropower:GND")
		(at 66.04 256.54 0)
		(unit 1)
		(exclude_from_sim no)
		(in_bom yes)
		(on_board yes)
		(dnp no)
		(property "Reference" "#PWR0165"
			(at 66.04 262.89 0)
			(effects
				(font
					(size 1.27 1.27)
				)
				(justify left bottom)
				(hide yes)
			)
		)
		(property "Value" "GND"
			(at 66.04 260.35 0)
			(effects
				(font
					(size 1.27 1.27)
					(thickness 0.15)
				)
			)
		)
		(property "Footprint" ""
			(at 74.93 264.16 0)
			(effects
				(font
					(size 1.27 1.27)
					(thickness 0.15)
				)
				(justify left bottom)
				(hide yes)
			)
		)
		(property "Datasheet" ""
			(at 74.93 269.24 0)
			(effects
				(font
					(size 1.27 1.27)
					(thickness 0.15)
				)
				(justify left bottom)
				(hide yes)
			)
		)
		(property "Description" ""
			(at 66.04 256.54 0)
			(effects
				(font
					(size 1.27 1.27)
				)
				(hide yes)
			)
		)
		(property "Author" "Antmicro"
			(at 74.93 264.16 0)
			(effects
				(font
					(size 1.27 1.27)
					(thickness 0.15)
				)
				(justify left bottom)
				(hide yes)
			)
		)
		(property "License" "Apache-2.0"
			(at 74.93 266.7 0)
			(effects
				(font
					(size 1.27 1.27)
					(thickness 0.15)
				)
				(justify left bottom)
				(hide yes)
			)
		)
		(pin "1"
		)
		(instances
			(project "jetson-orin-baseboard"
				(path ""
					(reference "#PWR0165")
					(unit 1)
				)
			)
		)
	)
	(symbol
		(lib_id "antmicroLEDIndicationDiscrete:LED_G_0603_LTST-C190GKT")
		(at 328.93 167.64 90)
		(unit 1)
		(exclude_from_sim no)
		(in_bom yes)
		(on_board yes)
		(dnp no)
		(fields_autoplaced yes)
		(property "Reference" "D25"
			(at 331.47 163.83 90)
			(effects
				(font
					(size 1.27 1.27)
				)
				(justify right)
			)
		)
		(property "Value" "LED_G_0603_LTST-C190GKT"
			(at 336.55 144.78 0)
			(effects
				(font
					(size 1.27 1.27)
					(thickness 0.15)
				)
				(justify left bottom)
				(hide yes)
			)
		)
		(property "Footprint" "antmicro-footprints:LED_0603_1608Metric_G"
			(at 339.09 144.78 0)
			(effects
				(font
					(size 1.27 1.27)
					(thickness 0.15)
				)
				(justify left bottom)
				(hide yes)
			)
		)
		(property "Datasheet" "https://media.digikey.com/pdf/Data%20Sheets/Lite-On%20PDFs/LTST-C190GKT.pdf"
			(at 341.63 144.78 0)
			(effects
				(font
					(size 1.27 1.27)
					(thickness 0.15)
				)
				(justify left bottom)
				(hide yes)
			)
		)
		(property "Description" ""
			(at 328.93 167.64 0)
			(effects
				(font
					(size 1.27 1.27)
				)
				(hide yes)
			)
		)
		(property "MPN" "LTST-C190GKT"
			(at 344.17 144.78 0)
			(effects
				(font
					(size 1.27 1.27)
					(thickness 0.15)
				)
				(justify left bottom)
				(hide yes)
			)
		)
		(property "Manufacturer" "Lite-On"
			(at 346.71 144.78 0)
			(effects
				(font
					(size 1.27 1.27)
					(thickness 0.15)
				)
				(justify left bottom)
				(hide yes)
			)
		)
		(property "Author" "Antmicro"
			(at 349.25 144.78 0)
			(effects
				(font
					(size 1.27 1.27)
					(thickness 0.15)
				)
				(justify left bottom)
				(hide yes)
			)
		)
		(property "License" "Apache-2.0"
			(at 351.79 144.78 0)
			(effects
				(font
					(size 1.27 1.27)
					(thickness 0.15)
				)
				(justify left bottom)
				(hide yes)
			)
		)
		(property "Color" "Green"
			(at 331.47 166.37 90)
			(effects
				(font
					(size 1.27 1.27)
				)
				(justify right)
			)
		)
		(pin "1"
		)
		(pin "2"
		)
		(instances
			(project "jetson-orin-baseboard"
				(path ""
					(reference "D25")
					(unit 1)
				)
			)
		)
	)
	(symbol
		(lib_id "antmicropower:GND")
		(at 246.38 168.91 0)
		(unit 1)
		(exclude_from_sim no)
		(in_bom yes)
		(on_board yes)
		(dnp no)
		(property "Reference" "#PWR0163"
			(at 246.38 175.26 0)
			(effects
				(font
					(size 1.27 1.27)
				)
				(justify left bottom)
				(hide yes)
			)
		)
		(property "Value" "GND"
			(at 246.38 172.72 0)
			(effects
				(font
					(size 1.27 1.27)
					(thickness 0.15)
				)
			)
		)
		(property "Footprint" ""
			(at 255.27 176.53 0)
			(effects
				(font
					(size 1.27 1.27)
					(thickness 0.15)
				)
				(justify left bottom)
				(hide yes)
			)
		)
		(property "Datasheet" ""
			(at 255.27 181.61 0)
			(effects
				(font
					(size 1.27 1.27)
					(thickness 0.15)
				)
				(justify left bottom)
				(hide yes)
			)
		)
		(property "Description" ""
			(at 246.38 168.91 0)
			(effects
				(font
					(size 1.27 1.27)
				)
				(hide yes)
			)
		)
		(property "Author" "Antmicro"
			(at 255.27 176.53 0)
			(effects
				(font
					(size 1.27 1.27)
					(thickness 0.15)
				)
				(justify left bottom)
				(hide yes)
			)
		)
		(property "License" "Apache-2.0"
			(at 255.27 179.07 0)
			(effects
				(font
					(size 1.27 1.27)
					(thickness 0.15)
				)
				(justify left bottom)
				(hide yes)
			)
		)
		(pin "1"
		)
		(instances
			(project "jetson-orin-baseboard"
				(path ""
					(reference "#PWR0163")
					(unit 1)
				)
			)
		)
	)
	(symbol
		(lib_id "antmicropower:+1V8")
		(at 334.01 195.58 0)
		(unit 1)
		(exclude_from_sim no)
		(in_bom yes)
		(on_board yes)
		(dnp no)
		(property "Reference" "#PWR0200"
			(at 334.01 199.39 0)
			(effects
				(font
					(size 1.27 1.27)
				)
				(justify left bottom)
				(hide yes)
			)
		)
		(property "Value" "+1V8"
			(at 330.835 191.77 0)
			(effects
				(font
					(size 1.27 1.27)
					(thickness 0.15)
				)
				(justify left)
			)
		)
		(property "Footprint" ""
			(at 349.25 203.2 0)
			(effects
				(font
					(size 1.27 1.27)
					(thickness 0.15)
				)
				(justify left bottom)
				(hide yes)
			)
		)
		(property "Datasheet" ""
			(at 349.25 205.74 0)
			(effects
				(font
					(size 1.27 1.27)
					(thickness 0.15)
				)
				(justify left bottom)
				(hide yes)
			)
		)
		(property "Description" ""
			(at 334.01 195.58 0)
			(effects
				(font
					(size 1.27 1.27)
				)
				(hide yes)
			)
		)
		(property "Author" "Antmicro"
			(at 349.25 200.66 0)
			(effects
				(font
					(size 1.27 1.27)
					(thickness 0.15)
				)
				(justify left bottom)
				(hide yes)
			)
		)
		(property "License" "Apache-2.0"
			(at 349.25 203.2 0)
			(effects
				(font
					(size 1.27 1.27)
					(thickness 0.15)
				)
				(justify left bottom)
				(hide yes)
			)
		)
		(pin "1"
		)
		(instances
			(project "jetson-orin-baseboard"
				(path ""
					(reference "#PWR0200")
					(unit 1)
				)
			)
		)
	)
	(symbol
		(lib_id "antmicroResistors0402:R_0R_0402")
		(at 35.56 82.55 90)
		(unit 1)
		(exclude_from_sim no)
		(in_bom no)
		(on_board yes)
		(dnp yes)
		(property "Reference" "R167"
			(at 36.83 78.74 90)
			(effects
				(font
					(size 1.27 1.27)
				)
				(justify right)
			)
		)
		(property "Value" "R_0R_0402"
			(at 48.26 62.23 0)
			(effects
				(font
					(size 1.27 1.27)
					(thickness 0.15)
				)
				(justify left bottom)
				(hide yes)
			)
		)
		(property "Footprint" "antmicro-footprints:R_0402_1005Metric"
			(at 50.8 62.23 0)
			(effects
				(font
					(size 1.27 1.27)
					(thickness 0.15)
				)
				(justify left bottom)
				(hide yes)
			)
		)
		(property "Datasheet" "https://industrial.panasonic.com/cdbs/www-data/pdf/RDA0000/AOA0000C301.pdf"
			(at 53.34 62.23 0)
			(effects
				(font
					(size 1.27 1.27)
					(thickness 0.15)
				)
				(justify left bottom)
				(hide yes)
			)
		)
		(property "Description" ""
			(at 35.56 82.55 0)
			(effects
				(font
					(size 1.27 1.27)
				)
				(hide yes)
			)
		)
		(property "Manufacturer" "Panasonic"
			(at 58.42 62.23 0)
			(effects
				(font
					(size 1.27 1.27)
					(thickness 0.15)
				)
				(justify left bottom)
				(hide yes)
			)
		)
		(property "MPN" "ERJ2GE0R00X"
			(at 55.88 62.23 0)
			(effects
				(font
					(size 1.27 1.27)
					(thickness 0.15)
				)
				(justify left bottom)
				(hide yes)
			)
		)
		(property "Val" "0R"
			(at 36.83 81.28 90)
			(effects
				(font
					(size 1.27 1.27)
					(thickness 0.15)
				)
				(justify right)
			)
		)
		(property "License" "Apache-2.0"
			(at 60.96 62.23 0)
			(effects
				(font
					(size 1.27 1.27)
					(thickness 0.15)
				)
				(justify left bottom)
				(hide yes)
			)
		)
		(property "Author" "Antmicro"
			(at 63.5 62.23 0)
			(effects
				(font
					(size 1.27 1.27)
					(thickness 0.15)
				)
				(justify left bottom)
				(hide yes)
			)
		)
		(property "Tolerance" "~"
			(at 45.72 62.23 0)
			(effects
				(font
					(size 1.27 1.27)
				)
				(justify left bottom)
				(hide yes)
			)
		)
		(property "Current" "1A"
			(at 66.04 62.23 0)
			(effects
				(font
					(size 1.27 1.27)
					(thickness 0.15)
				)
				(justify left bottom)
				(hide yes)
			)
		)
		(pin "1"
		)
		(pin "2"
		)
		(instances
			(project "jetson-orin-baseboard"
				(path ""
					(reference "R167")
					(unit 1)
				)
			)
		)
	)
	(symbol
		(lib_id "antmicroResistorNetworksArrays:R_4x2k2_0201_array")
		(at 41.91 151.13 90)
		(unit 1)
		(exclude_from_sim no)
		(in_bom yes)
		(on_board yes)
		(dnp no)
		(fields_autoplaced yes)
		(property "Reference" "R36"
			(at 52.07 144.78 90)
			(effects
				(font
					(size 1.27 1.27)
				)
				(justify right)
			)
		)
		(property "Value" "R_4x2k2_0201_array"
			(at 49.53 124.46 0)
			(effects
				(font
					(size 1.27 1.27)
					(thickness 0.15)
				)
				(justify left bottom)
				(hide yes)
			)
		)
		(property "Footprint" "antmicro-footprints:R_Array_4x0201_Panasonic_EXB18V"
			(at 54.61 124.46 0)
			(effects
				(font
					(size 1.27 1.27)
					(thickness 0.15)
				)
				(justify left bottom)
				(hide yes)
			)
		)
		(property "Datasheet" "http://industrial.panasonic.com/cdbs/www-data/pdf/AOC0000/AOC0000C14.pdf"
			(at 57.15 124.46 0)
			(effects
				(font
					(size 1.27 1.27)
					(thickness 0.15)
				)
				(justify left bottom)
				(hide yes)
			)
		)
		(property "Description" ""
			(at 41.91 151.13 0)
			(effects
				(font
					(size 1.27 1.27)
				)
				(hide yes)
			)
		)
		(property "MPN" "EXB-18V222JX"
			(at 59.69 124.46 0)
			(effects
				(font
					(size 1.27 1.27)
					(thickness 0.15)
				)
				(justify left bottom)
				(hide yes)
			)
		)
		(property "Manufacturer" "Panasonic"
			(at 62.23 124.46 0)
			(effects
				(font
					(size 1.27 1.27)
					(thickness 0.15)
				)
				(justify left bottom)
				(hide yes)
			)
		)
		(property "Val" "4x2k2_0201"
			(at 52.07 147.32 90)
			(effects
				(font
					(size 1.27 1.27)
					(thickness 0.15)
				)
				(justify right)
			)
		)
		(property "Author" "Antmicro"
			(at 64.77 124.46 0)
			(effects
				(font
					(size 1.27 1.27)
					(thickness 0.15)
				)
				(justify left bottom)
				(hide yes)
			)
		)
		(property "License" "Apache-2.0"
			(at 67.31 124.46 0)
			(effects
				(font
					(size 1.27 1.27)
					(thickness 0.15)
				)
				(justify left bottom)
				(hide yes)
			)
		)
		(pin "1"
		)
		(pin "2"
		)
		(pin "3"
		)
		(pin "4"
		)
		(pin "5"
		)
		(pin "6"
		)
		(pin "7"
		)
		(pin "8"
		)
		(instances
			(project "jetson-orin-baseboard"
				(path ""
					(reference "R36")
					(unit 1)
				)
			)
		)
	)
	(symbol
		(lib_id "antmicroTestPoints:TP_0.75mm_SMD")
		(at 97.79 101.6 0)
		(unit 1)
		(exclude_from_sim no)
		(in_bom no)
		(on_board yes)
		(dnp no)
		(property "Reference" "TP42"
			(at 104.14 101.6 0)
			(effects
				(font
					(size 1.27 1.27)
				)
			)
		)
		(property "Value" "TP_0.75mm_SMD"
			(at 107.95 105.41 0)
			(effects
				(font
					(size 1.27 1.27)
					(thickness 0.15)
				)
				(justify left bottom)
				(hide yes)
			)
		)
		(property "Footprint" "antmicro-footprints:TP_SMD_0.75mm"
			(at 107.95 107.95 0)
			(effects
				(font
					(size 1.27 1.27)
					(thickness 0.15)
				)
				(justify left bottom)
				(hide yes)
			)
		)
		(property "Datasheet" ""
			(at 115.57 114.3 0)
			(effects
				(font
					(size 1.27 1.27)
					(thickness 0.15)
				)
				(justify left bottom)
				(hide yes)
			)
		)
		(property "Description" ""
			(at 97.79 101.6 0)
			(effects
				(font
					(size 1.27 1.27)
				)
				(hide yes)
			)
		)
		(property "MPN" ""
			(at 108.585 113.03 0)
			(effects
				(font
					(size 1.27 1.27)
					(thickness 0.15)
				)
				(justify left bottom)
				(hide yes)
			)
		)
		(property "Manufacturer" ""
			(at 108.585 107.95 0)
			(effects
				(font
					(size 1.27 1.27)
					(thickness 0.15)
				)
				(justify left bottom)
				(hide yes)
			)
		)
		(property "Author" "Antmicro"
			(at 107.95 110.49 0)
			(effects
				(font
					(size 1.27 1.27)
					(thickness 0.15)
				)
				(justify left bottom)
				(hide yes)
			)
		)
		(property "License" "Apache-2.0"
			(at 107.95 113.03 0)
			(effects
				(font
					(size 1.27 1.27)
					(thickness 0.15)
				)
				(justify left bottom)
				(hide yes)
			)
		)
		(pin "1"
		)
		(instances
			(project "jetson-orin-baseboard"
				(path ""
					(reference "TP42")
					(unit 1)
				)
			)
		)
	)
	(symbol
		(lib_id "antmicropower:GND")
		(at 76.2 209.55 0)
		(unit 1)
		(exclude_from_sim no)
		(in_bom yes)
		(on_board yes)
		(dnp no)
		(property "Reference" "#PWR0192"
			(at 76.2 215.9 0)
			(effects
				(font
					(size 1.27 1.27)
				)
				(justify left bottom)
				(hide yes)
			)
		)
		(property "Value" "GND"
			(at 76.2 213.36 0)
			(effects
				(font
					(size 1.27 1.27)
					(thickness 0.15)
				)
			)
		)
		(property "Footprint" ""
			(at 85.09 217.17 0)
			(effects
				(font
					(size 1.27 1.27)
					(thickness 0.15)
				)
				(justify left bottom)
				(hide yes)
			)
		)
		(property "Datasheet" ""
			(at 85.09 222.25 0)
			(effects
				(font
					(size 1.27 1.27)
					(thickness 0.15)
				)
				(justify left bottom)
				(hide yes)
			)
		)
		(property "Description" ""
			(at 76.2 209.55 0)
			(effects
				(font
					(size 1.27 1.27)
				)
				(hide yes)
			)
		)
		(property "Author" "Antmicro"
			(at 85.09 217.17 0)
			(effects
				(font
					(size 1.27 1.27)
					(thickness 0.15)
				)
				(justify left bottom)
				(hide yes)
			)
		)
		(property "License" "Apache-2.0"
			(at 85.09 219.71 0)
			(effects
				(font
					(size 1.27 1.27)
					(thickness 0.15)
				)
				(justify left bottom)
				(hide yes)
			)
		)
		(pin "1"
		)
		(instances
			(project "jetson-orin-baseboard"
				(path ""
					(reference "#PWR0192")
					(unit 1)
				)
			)
		)
	)
	(symbol
		(lib_id "antmicroResistors0402:R_470R_0402")
		(at 328.93 161.29 90)
		(unit 1)
		(exclude_from_sim no)
		(in_bom yes)
		(on_board yes)
		(dnp no)
		(fields_autoplaced yes)
		(property "Reference" "R206"
			(at 330.835 157.48 90)
			(effects
				(font
					(size 1.27 1.27)
				)
				(justify right)
			)
		)
		(property "Value" "R_470R_0402"
			(at 341.63 140.97 0)
			(effects
				(font
					(size 1.27 1.27)
					(thickness 0.15)
				)
				(justify left bottom)
				(hide yes)
			)
		)
		(property "Footprint" "antmicro-footprints:R_0402_1005Metric"
			(at 344.17 140.97 0)
			(effects
				(font
					(size 1.27 1.27)
					(thickness 0.15)
				)
				(justify left bottom)
				(hide yes)
			)
		)
		(property "Datasheet" "https://www.bourns.com/docs/product-datasheets/cr.pdf"
			(at 346.71 140.97 0)
			(effects
				(font
					(size 1.27 1.27)
					(thickness 0.15)
				)
				(justify left bottom)
				(hide yes)
			)
		)
		(property "Description" ""
			(at 328.93 161.29 0)
			(effects
				(font
					(size 1.27 1.27)
				)
				(hide yes)
			)
		)
		(property "Manufacturer" "Bourns"
			(at 351.79 140.97 0)
			(effects
				(font
					(size 1.27 1.27)
					(thickness 0.15)
				)
				(justify left bottom)
				(hide yes)
			)
		)
		(property "MPN" "CR0402-FX-4700GLF"
			(at 349.25 140.97 0)
			(effects
				(font
					(size 1.27 1.27)
					(thickness 0.15)
				)
				(justify left bottom)
				(hide yes)
			)
		)
		(property "Val" "470R"
			(at 330.835 160.02 90)
			(effects
				(font
					(size 1.27 1.27)
					(thickness 0.15)
				)
				(justify right)
			)
		)
		(property "License" "Apache-2.0"
			(at 354.33 140.97 0)
			(effects
				(font
					(size 1.27 1.27)
					(thickness 0.15)
				)
				(justify left bottom)
				(hide yes)
			)
		)
		(property "Author" "Antmicro"
			(at 356.87 140.97 0)
			(effects
				(font
					(size 1.27 1.27)
					(thickness 0.15)
				)
				(justify left bottom)
				(hide yes)
			)
		)
		(property "Tolerance" "1%"
			(at 339.09 140.97 0)
			(effects
				(font
					(size 1.27 1.27)
				)
				(justify left bottom)
				(hide yes)
			)
		)
		(pin "1"
		)
		(pin "2"
		)
		(instances
			(project "jetson-orin-baseboard"
				(path ""
					(reference "R206")
					(unit 1)
				)
			)
		)
	)
	(symbol
		(lib_id "antmicropower:GND")
		(at 232.41 220.98 0)
		(unit 1)
		(exclude_from_sim no)
		(in_bom yes)
		(on_board yes)
		(dnp no)
		(property "Reference" "#PWR0363"
			(at 232.41 227.33 0)
			(effects
				(font
					(size 1.27 1.27)
				)
				(justify left bottom)
				(hide yes)
			)
		)
		(property "Value" "GND"
			(at 232.41 224.79 0)
			(effects
				(font
					(size 1.27 1.27)
					(thickness 0.15)
				)
			)
		)
		(property "Footprint" ""
			(at 241.3 228.6 0)
			(effects
				(font
					(size 1.27 1.27)
					(thickness 0.15)
				)
				(justify left bottom)
				(hide yes)
			)
		)
		(property "Datasheet" ""
			(at 241.3 233.68 0)
			(effects
				(font
					(size 1.27 1.27)
					(thickness 0.15)
				)
				(justify left bottom)
				(hide yes)
			)
		)
		(property "Description" ""
			(at 232.41 220.98 0)
			(effects
				(font
					(size 1.27 1.27)
				)
				(hide yes)
			)
		)
		(property "Author" "Antmicro"
			(at 241.3 228.6 0)
			(effects
				(font
					(size 1.27 1.27)
					(thickness 0.15)
				)
				(justify left bottom)
				(hide yes)
			)
		)
		(property "License" "Apache-2.0"
			(at 241.3 231.14 0)
			(effects
				(font
					(size 1.27 1.27)
					(thickness 0.15)
				)
				(justify left bottom)
				(hide yes)
			)
		)
		(pin "1"
		)
		(instances
			(project "jetson-orin-baseboard"
				(path ""
					(reference "#PWR0363")
					(unit 1)
				)
			)
		)
	)
	(symbol
		(lib_id "antmicroCapacitors0402:C_100n_0402")
		(at 185.42 203.2 90)
		(mirror x)
		(unit 1)
		(exclude_from_sim no)
		(in_bom yes)
		(on_board yes)
		(dnp no)
		(property "Reference" "C90"
			(at 187.325 204.47 90)
			(effects
				(font
					(size 1.27 1.27)
				)
				(justify right)
			)
		)
		(property "Value" "C_100n_0402"
			(at 195.58 223.52 0)
			(effects
				(font
					(size 1.27 1.27)
					(thickness 0.15)
				)
				(justify left bottom)
				(hide yes)
			)
		)
		(property "Footprint" "antmicro-footprints:C_0402_1005Metric"
			(at 198.12 223.52 0)
			(effects
				(font
					(size 1.27 1.27)
					(thickness 0.15)
				)
				(justify left bottom)
				(hide yes)
			)
		)
		(property "Datasheet" "https://www.murata.com/products/productdetail?partno=GRM155R61H104KE14%23"
			(at 200.66 223.52 0)
			(effects
				(font
					(size 1.27 1.27)
					(thickness 0.15)
				)
				(justify left bottom)
				(hide yes)
			)
		)
		(property "Description" ""
			(at 185.42 203.2 0)
			(effects
				(font
					(size 1.27 1.27)
				)
				(hide yes)
			)
		)
		(property "Manufacturer" "Murata"
			(at 205.74 223.52 0)
			(effects
				(font
					(size 1.27 1.27)
					(thickness 0.15)
				)
				(justify left bottom)
				(hide yes)
			)
		)
		(property "MPN" "GRM155R61H104KE14D"
			(at 203.2 223.52 0)
			(effects
				(font
					(size 1.27 1.27)
					(thickness 0.15)
				)
				(justify left bottom)
				(hide yes)
			)
		)
		(property "Val" "100n"
			(at 187.325 207.01 90)
			(effects
				(font
					(size 1.27 1.27)
					(thickness 0.15)
				)
				(justify right)
			)
		)
		(property "License" "Apache-2.0"
			(at 208.28 223.52 0)
			(effects
				(font
					(size 1.27 1.27)
					(thickness 0.15)
				)
				(justify left bottom)
				(hide yes)
			)
		)
		(property "Author" "Antmicro"
			(at 210.82 223.52 0)
			(effects
				(font
					(size 1.27 1.27)
					(thickness 0.15)
				)
				(justify left bottom)
				(hide yes)
			)
		)
		(property "Voltage" "50V"
			(at 213.36 223.52 0)
			(effects
				(font
					(size 1.27 1.27)
				)
				(justify left bottom)
				(hide yes)
			)
		)
		(property "Dielectric" "X5R"
			(at 215.9 223.52 0)
			(effects
				(font
					(size 1.27 1.27)
				)
				(justify left bottom)
				(hide yes)
			)
		)
		(pin "1"
		)
		(pin "2"
		)
		(instances
			(project "jetson-orin-baseboard"
				(path ""
					(reference "C90")
					(unit 1)
				)
			)
		)
	)
	(symbol
		(lib_id "antmicroResistors0402:R_470R_0402")
		(at 251.46 161.29 90)
		(unit 1)
		(exclude_from_sim no)
		(in_bom yes)
		(on_board yes)
		(dnp no)
		(fields_autoplaced yes)
		(property "Reference" "R197"
			(at 254 157.48 90)
			(effects
				(font
					(size 1.27 1.27)
				)
				(justify right)
			)
		)
		(property "Value" "R_470R_0402"
			(at 264.16 140.97 0)
			(effects
				(font
					(size 1.27 1.27)
					(thickness 0.15)
				)
				(justify left bottom)
				(hide yes)
			)
		)
		(property "Footprint" "antmicro-footprints:R_0402_1005Metric"
			(at 266.7 140.97 0)
			(effects
				(font
					(size 1.27 1.27)
					(thickness 0.15)
				)
				(justify left bottom)
				(hide yes)
			)
		)
		(property "Datasheet" "https://www.bourns.com/docs/product-datasheets/cr.pdf"
			(at 269.24 140.97 0)
			(effects
				(font
					(size 1.27 1.27)
					(thickness 0.15)
				)
				(justify left bottom)
				(hide yes)
			)
		)
		(property "Description" ""
			(at 251.46 161.29 0)
			(effects
				(font
					(size 1.27 1.27)
				)
				(hide yes)
			)
		)
		(property "Manufacturer" "Bourns"
			(at 274.32 140.97 0)
			(effects
				(font
					(size 1.27 1.27)
					(thickness 0.15)
				)
				(justify left bottom)
				(hide yes)
			)
		)
		(property "MPN" "CR0402-FX-4700GLF"
			(at 271.78 140.97 0)
			(effects
				(font
					(size 1.27 1.27)
					(thickness 0.15)
				)
				(justify left bottom)
				(hide yes)
			)
		)
		(property "Val" "470R"
			(at 254 160.02 90)
			(effects
				(font
					(size 1.27 1.27)
					(thickness 0.15)
				)
				(justify right)
			)
		)
		(property "License" "Apache-2.0"
			(at 276.86 140.97 0)
			(effects
				(font
					(size 1.27 1.27)
					(thickness 0.15)
				)
				(justify left bottom)
				(hide yes)
			)
		)
		(property "Author" "Antmicro"
			(at 279.4 140.97 0)
			(effects
				(font
					(size 1.27 1.27)
					(thickness 0.15)
				)
				(justify left bottom)
				(hide yes)
			)
		)
		(property "Tolerance" "1%"
			(at 261.62 140.97 0)
			(effects
				(font
					(size 1.27 1.27)
				)
				(justify left bottom)
				(hide yes)
			)
		)
		(pin "1"
		)
		(pin "2"
		)
		(instances
			(project "jetson-orin-baseboard"
				(path ""
					(reference "R197")
					(unit 1)
				)
			)
		)
	)
	(symbol
		(lib_id "antmicroLEDIndicationDiscrete:LED_G_0603_LTST-C190GKT")
		(at 323.85 167.64 90)
		(unit 1)
		(exclude_from_sim no)
		(in_bom yes)
		(on_board yes)
		(dnp no)
		(fields_autoplaced yes)
		(property "Reference" "D24"
			(at 320.04 163.83 90)
			(effects
				(font
					(size 1.27 1.27)
				)
				(justify left)
			)
		)
		(property "Value" "LED_G_0603_LTST-C190GKT"
			(at 331.47 144.78 0)
			(effects
				(font
					(size 1.27 1.27)
					(thickness 0.15)
				)
				(justify left bottom)
				(hide yes)
			)
		)
		(property "Footprint" "antmicro-footprints:LED_0603_1608Metric_G"
			(at 334.01 144.78 0)
			(effects
				(font
					(size 1.27 1.27)
					(thickness 0.15)
				)
				(justify left bottom)
				(hide yes)
			)
		)
		(property "Datasheet" "https://media.digikey.com/pdf/Data%20Sheets/Lite-On%20PDFs/LTST-C190GKT.pdf"
			(at 336.55 144.78 0)
			(effects
				(font
					(size 1.27 1.27)
					(thickness 0.15)
				)
				(justify left bottom)
				(hide yes)
			)
		)
		(property "Description" ""
			(at 323.85 167.64 0)
			(effects
				(font
					(size 1.27 1.27)
				)
				(hide yes)
			)
		)
		(property "MPN" "LTST-C190GKT"
			(at 339.09 144.78 0)
			(effects
				(font
					(size 1.27 1.27)
					(thickness 0.15)
				)
				(justify left bottom)
				(hide yes)
			)
		)
		(property "Manufacturer" "Lite-On"
			(at 341.63 144.78 0)
			(effects
				(font
					(size 1.27 1.27)
					(thickness 0.15)
				)
				(justify left bottom)
				(hide yes)
			)
		)
		(property "Author" "Antmicro"
			(at 344.17 144.78 0)
			(effects
				(font
					(size 1.27 1.27)
					(thickness 0.15)
				)
				(justify left bottom)
				(hide yes)
			)
		)
		(property "License" "Apache-2.0"
			(at 346.71 144.78 0)
			(effects
				(font
					(size 1.27 1.27)
					(thickness 0.15)
				)
				(justify left bottom)
				(hide yes)
			)
		)
		(property "Color" "Green"
			(at 320.04 166.37 90)
			(effects
				(font
					(size 1.27 1.27)
				)
				(justify left)
			)
		)
		(pin "1"
		)
		(pin "2"
		)
		(instances
			(project "jetson-orin-baseboard"
				(path ""
					(reference "D24")
					(unit 1)
				)
			)
		)
	)
	(symbol
		(lib_id "antmicroResistors0402:R_10k_0402")
		(at 175.26 208.28 90)
		(unit 1)
		(exclude_from_sim no)
		(in_bom no)
		(on_board yes)
		(dnp yes)
		(property "Reference" "R194"
			(at 176.53 204.47 90)
			(effects
				(font
					(size 1.27 1.27)
				)
				(justify right)
			)
		)
		(property "Value" "R_10k_0402"
			(at 187.96 187.96 0)
			(effects
				(font
					(size 1.27 1.27)
					(thickness 0.15)
				)
				(justify left bottom)
				(hide yes)
			)
		)
		(property "Footprint" "antmicro-footprints:R_0402_1005Metric"
			(at 190.5 187.96 0)
			(effects
				(font
					(size 1.27 1.27)
					(thickness 0.15)
				)
				(justify left bottom)
				(hide yes)
			)
		)
		(property "Datasheet" "https://www.bourns.com/docs/product-datasheets/cr.pdf"
			(at 193.04 187.96 0)
			(effects
				(font
					(size 1.27 1.27)
					(thickness 0.15)
				)
				(justify left bottom)
				(hide yes)
			)
		)
		(property "Description" ""
			(at 175.26 208.28 0)
			(effects
				(font
					(size 1.27 1.27)
				)
				(hide yes)
			)
		)
		(property "Manufacturer" "Bourns"
			(at 198.12 187.96 0)
			(effects
				(font
					(size 1.27 1.27)
					(thickness 0.15)
				)
				(justify left bottom)
				(hide yes)
			)
		)
		(property "MPN" "CR0402-FX-1002GLF"
			(at 195.58 187.96 0)
			(effects
				(font
					(size 1.27 1.27)
					(thickness 0.15)
				)
				(justify left bottom)
				(hide yes)
			)
		)
		(property "Val" "10k"
			(at 176.53 207.01 90)
			(effects
				(font
					(size 1.27 1.27)
					(thickness 0.15)
				)
				(justify right)
			)
		)
		(property "License" "Apache-2.0"
			(at 200.66 187.96 0)
			(effects
				(font
					(size 1.27 1.27)
					(thickness 0.15)
				)
				(justify left bottom)
				(hide yes)
			)
		)
		(property "Author" "Antmicro"
			(at 203.2 187.96 0)
			(effects
				(font
					(size 1.27 1.27)
					(thickness 0.15)
				)
				(justify left bottom)
				(hide yes)
			)
		)
		(property "Tolerance" "1%"
			(at 185.42 187.96 0)
			(effects
				(font
					(size 1.27 1.27)
				)
				(justify left bottom)
				(hide yes)
			)
		)
		(pin "1"
		)
		(pin "2"
		)
		(instances
			(project "jetson-orin-baseboard"
				(path ""
					(reference "R194")
					(unit 1)
				)
			)
		)
	)
	(symbol
		(lib_id "antmicropower:+5V")
		(at 185.42 200.66 0)
		(unit 1)
		(exclude_from_sim no)
		(in_bom yes)
		(on_board yes)
		(dnp no)
		(property "Reference" "#PWR0168"
			(at 185.42 204.47 0)
			(effects
				(font
					(size 1.27 1.27)
				)
				(justify left bottom)
				(hide yes)
			)
		)
		(property "Value" "+5V"
			(at 182.88 196.85 0)
			(effects
				(font
					(size 1.27 1.27)
					(thickness 0.15)
				)
				(justify left)
			)
		)
		(property "Footprint" ""
			(at 200.66 208.28 0)
			(effects
				(font
					(size 1.27 1.27)
					(thickness 0.15)
				)
				(justify left bottom)
				(hide yes)
			)
		)
		(property "Datasheet" ""
			(at 200.66 210.82 0)
			(effects
				(font
					(size 1.27 1.27)
					(thickness 0.15)
				)
				(justify left bottom)
				(hide yes)
			)
		)
		(property "Description" ""
			(at 185.42 200.66 0)
			(effects
				(font
					(size 1.27 1.27)
				)
				(hide yes)
			)
		)
		(property "Author" "Antmicro"
			(at 200.66 208.28 0)
			(effects
				(font
					(size 1.27 1.27)
					(thickness 0.15)
				)
				(justify left bottom)
				(hide yes)
			)
		)
		(property "License" "Apache-2.0"
			(at 200.66 210.82 0)
			(effects
				(font
					(size 1.27 1.27)
					(thickness 0.15)
				)
				(justify left bottom)
				(hide yes)
			)
		)
		(pin "1"
		)
		(instances
			(project "jetson-orin-baseboard"
				(path ""
					(reference "#PWR0168")
					(unit 1)
				)
			)
		)
	)
	(symbol
		(lib_id "antmicroPMICPowerDistributionSwitchesLoadDrivers:AP22615A_TSOT26")
		(at 201.93 243.84 0)
		(unit 1)
		(exclude_from_sim no)
		(in_bom yes)
		(on_board yes)
		(dnp no)
		(property "Reference" "U28"
			(at 209.55 237.49 0)
			(effects
				(font
					(size 1.27 1.27)
				)
			)
		)
		(property "Value" "AP22615A_TSOT26"
			(at 232.41 248.92 0)
			(effects
				(font
					(size 1.27 1.27)
					(thickness 0.15)
				)
				(justify left bottom)
				(hide yes)
			)
		)
		(property "Footprint" "antmicro-footprints:TSOT23-6"
			(at 232.41 251.46 0)
			(effects
				(font
					(size 1.27 1.27)
					(thickness 0.15)
				)
				(justify left bottom)
				(hide yes)
			)
		)
		(property "Datasheet" "https://www.mouser.com/datasheet/2/115/DIOD_S_A0008958405_1-2543193.pdf"
			(at 232.41 254 0)
			(effects
				(font
					(size 1.27 1.27)
					(thickness 0.15)
				)
				(justify left bottom)
				(hide yes)
			)
		)
		(property "Description" ""
			(at 201.93 243.84 0)
			(effects
				(font
					(size 1.27 1.27)
				)
				(hide yes)
			)
		)
		(property "MPN" "AP22615AWU-7"
			(at 209.55 240.03 0)
			(effects
				(font
					(size 1.27 1.27)
					(thickness 0.15)
				)
			)
		)
		(property "Manufacturer" "Diodes Incorporated"
			(at 232.41 259.08 0)
			(effects
				(font
					(size 1.27 1.27)
					(thickness 0.15)
				)
				(justify left bottom)
				(hide yes)
			)
		)
		(property "Author" "Antmicro"
			(at 232.41 261.62 0)
			(effects
				(font
					(size 1.27 1.27)
					(thickness 0.15)
				)
				(justify left bottom)
				(hide yes)
			)
		)
		(property "License" "Apache-2.0"
			(at 232.41 264.16 0)
			(effects
				(font
					(size 1.27 1.27)
					(thickness 0.15)
				)
				(justify left bottom)
				(hide yes)
			)
		)
		(pin "1"
		)
		(pin "2"
		)
		(pin "3"
		)
		(pin "4"
		)
		(pin "5"
		)
		(pin "6"
		)
		(instances
			(project "jetson-orin-baseboard"
				(path ""
					(reference "U28")
					(unit 1)
				)
			)
		)
	)
	(symbol
		(lib_id "antmicropower:GND")
		(at 334.01 204.47 0)
		(unit 1)
		(exclude_from_sim no)
		(in_bom yes)
		(on_board yes)
		(dnp no)
		(property "Reference" "#PWR0164"
			(at 334.01 210.82 0)
			(effects
				(font
					(size 1.27 1.27)
				)
				(justify left bottom)
				(hide yes)
			)
		)
		(property "Value" "GND"
			(at 334.01 208.28 0)
			(effects
				(font
					(size 1.27 1.27)
					(thickness 0.15)
				)
			)
		)
		(property "Footprint" ""
			(at 342.9 212.09 0)
			(effects
				(font
					(size 1.27 1.27)
					(thickness 0.15)
				)
				(justify left bottom)
				(hide yes)
			)
		)
		(property "Datasheet" ""
			(at 342.9 217.17 0)
			(effects
				(font
					(size 1.27 1.27)
					(thickness 0.15)
				)
				(justify left bottom)
				(hide yes)
			)
		)
		(property "Description" ""
			(at 334.01 204.47 0)
			(effects
				(font
					(size 1.27 1.27)
				)
				(hide yes)
			)
		)
		(property "Author" "Antmicro"
			(at 342.9 212.09 0)
			(effects
				(font
					(size 1.27 1.27)
					(thickness 0.15)
				)
				(justify left bottom)
				(hide yes)
			)
		)
		(property "License" "Apache-2.0"
			(at 342.9 214.63 0)
			(effects
				(font
					(size 1.27 1.27)
					(thickness 0.15)
				)
				(justify left bottom)
				(hide yes)
			)
		)
		(pin "1"
		)
		(instances
			(project "jetson-orin-baseboard"
				(path ""
					(reference "#PWR0164")
					(unit 1)
				)
			)
		)
	)
	(symbol
		(lib_id "antmicroResistors0402:R_100k_0402")
		(at 175.26 255.27 90)
		(unit 1)
		(exclude_from_sim no)
		(in_bom yes)
		(on_board yes)
		(dnp no)
		(property "Reference" "R180"
			(at 176.53 251.46 90)
			(effects
				(font
					(size 1.27 1.27)
				)
				(justify right)
			)
		)
		(property "Value" "R_100k_0402"
			(at 187.96 234.95 0)
			(effects
				(font
					(size 1.27 1.27)
					(thickness 0.15)
				)
				(justify left bottom)
				(hide yes)
			)
		)
		(property "Footprint" "antmicro-footprints:R_0402_1005Metric"
			(at 190.5 234.95 0)
			(effects
				(font
					(size 1.27 1.27)
					(thickness 0.15)
				)
				(justify left bottom)
				(hide yes)
			)
		)
		(property "Datasheet" "https://www.bourns.com/docs/product-datasheets/cr.pdf"
			(at 193.04 234.95 0)
			(effects
				(font
					(size 1.27 1.27)
					(thickness 0.15)
				)
				(justify left bottom)
				(hide yes)
			)
		)
		(property "Description" ""
			(at 175.26 255.27 0)
			(effects
				(font
					(size 1.27 1.27)
				)
				(hide yes)
			)
		)
		(property "Manufacturer" "Bourns"
			(at 198.12 234.95 0)
			(effects
				(font
					(size 1.27 1.27)
					(thickness 0.15)
				)
				(justify left bottom)
				(hide yes)
			)
		)
		(property "MPN" "CR0402-FX-1003GLF"
			(at 195.58 234.95 0)
			(effects
				(font
					(size 1.27 1.27)
					(thickness 0.15)
				)
				(justify left bottom)
				(hide yes)
			)
		)
		(property "Val" "100k"
			(at 176.53 254 90)
			(effects
				(font
					(size 1.27 1.27)
					(thickness 0.15)
				)
				(justify right)
			)
		)
		(property "License" "Apache-2.0"
			(at 200.66 234.95 0)
			(effects
				(font
					(size 1.27 1.27)
					(thickness 0.15)
				)
				(justify left bottom)
				(hide yes)
			)
		)
		(property "Author" "Antmicro"
			(at 203.2 234.95 0)
			(effects
				(font
					(size 1.27 1.27)
					(thickness 0.15)
				)
				(justify left bottom)
				(hide yes)
			)
		)
		(property "Tolerance" "1%"
			(at 185.42 234.95 0)
			(effects
				(font
					(size 1.27 1.27)
				)
				(justify left bottom)
				(hide yes)
			)
		)
		(pin "1"
		)
		(pin "2"
		)
		(instances
			(project "jetson-orin-baseboard"
				(path ""
					(reference "R180")
					(unit 1)
				)
			)
		)
	)
	(symbol
		(lib_id "antmicropower:GND")
		(at 109.22 220.98 0)
		(unit 1)
		(exclude_from_sim no)
		(in_bom yes)
		(on_board yes)
		(dnp no)
		(property "Reference" "#PWR0162"
			(at 109.22 227.33 0)
			(effects
				(font
					(size 1.27 1.27)
				)
				(justify left bottom)
				(hide yes)
			)
		)
		(property "Value" "GND"
			(at 109.22 224.79 0)
			(effects
				(font
					(size 1.27 1.27)
					(thickness 0.15)
				)
			)
		)
		(property "Footprint" ""
			(at 118.11 228.6 0)
			(effects
				(font
					(size 1.27 1.27)
					(thickness 0.15)
				)
				(justify left bottom)
				(hide yes)
			)
		)
		(property "Datasheet" ""
			(at 118.11 233.68 0)
			(effects
				(font
					(size 1.27 1.27)
					(thickness 0.15)
				)
				(justify left bottom)
				(hide yes)
			)
		)
		(property "Description" ""
			(at 109.22 220.98 0)
			(effects
				(font
					(size 1.27 1.27)
				)
				(hide yes)
			)
		)
		(property "Author" "Antmicro"
			(at 118.11 228.6 0)
			(effects
				(font
					(size 1.27 1.27)
					(thickness 0.15)
				)
				(justify left bottom)
				(hide yes)
			)
		)
		(property "License" "Apache-2.0"
			(at 118.11 231.14 0)
			(effects
				(font
					(size 1.27 1.27)
					(thickness 0.15)
				)
				(justify left bottom)
				(hide yes)
			)
		)
		(pin "1"
		)
		(instances
			(project "jetson-orin-baseboard"
				(path ""
					(reference "#PWR0162")
					(unit 1)
				)
			)
		)
	)
	(symbol
		(lib_id "antmicropower:+3V3")
		(at 26.67 129.54 0)
		(unit 1)
		(exclude_from_sim no)
		(in_bom yes)
		(on_board yes)
		(dnp no)
		(property "Reference" "#PWR0157"
			(at 26.67 133.35 0)
			(effects
				(font
					(size 1.27 1.27)
				)
				(justify left bottom)
				(hide yes)
			)
		)
		(property "Value" "+3V3"
			(at 26.035 125.73 0)
			(effects
				(font
					(size 1.27 1.27)
					(thickness 0.15)
				)
			)
		)
		(property "Footprint" ""
			(at 41.91 137.16 0)
			(effects
				(font
					(size 1.27 1.27)
					(thickness 0.15)
				)
				(justify left bottom)
				(hide yes)
			)
		)
		(property "Datasheet" ""
			(at 41.91 139.7 0)
			(effects
				(font
					(size 1.27 1.27)
					(thickness 0.15)
				)
				(justify left bottom)
				(hide yes)
			)
		)
		(property "Description" ""
			(at 26.67 129.54 0)
			(effects
				(font
					(size 1.27 1.27)
				)
				(hide yes)
			)
		)
		(property "Author" "Antmicro"
			(at 41.91 132.08 0)
			(effects
				(font
					(size 1.27 1.27)
					(thickness 0.15)
				)
				(justify left bottom)
				(hide yes)
			)
		)
		(property "License" "Apache-2.0"
			(at 41.91 134.62 0)
			(effects
				(font
					(size 1.27 1.27)
					(thickness 0.15)
				)
				(justify left bottom)
				(hide yes)
			)
		)
		(pin "1"
		)
		(instances
			(project "jetson-orin-baseboard"
				(path ""
					(reference "#PWR0157")
					(unit 1)
				)
			)
		)
	)
	(symbol
		(lib_id "antmicropower:GND")
		(at 361.95 163.83 0)
		(unit 1)
		(exclude_from_sim no)
		(in_bom yes)
		(on_board yes)
		(dnp no)
		(property "Reference" "#PWR0202"
			(at 361.95 170.18 0)
			(effects
				(font
					(size 1.27 1.27)
				)
				(justify left bottom)
				(hide yes)
			)
		)
		(property "Value" "GND"
			(at 361.95 167.64 0)
			(effects
				(font
					(size 1.27 1.27)
					(thickness 0.15)
				)
			)
		)
		(property "Footprint" ""
			(at 370.84 171.45 0)
			(effects
				(font
					(size 1.27 1.27)
					(thickness 0.15)
				)
				(justify left bottom)
				(hide yes)
			)
		)
		(property "Datasheet" ""
			(at 370.84 176.53 0)
			(effects
				(font
					(size 1.27 1.27)
					(thickness 0.15)
				)
				(justify left bottom)
				(hide yes)
			)
		)
		(property "Description" ""
			(at 361.95 163.83 0)
			(effects
				(font
					(size 1.27 1.27)
				)
				(hide yes)
			)
		)
		(property "Author" "Antmicro"
			(at 370.84 171.45 0)
			(effects
				(font
					(size 1.27 1.27)
					(thickness 0.15)
				)
				(justify left bottom)
				(hide yes)
			)
		)
		(property "License" "Apache-2.0"
			(at 370.84 173.99 0)
			(effects
				(font
					(size 1.27 1.27)
					(thickness 0.15)
				)
				(justify left bottom)
				(hide yes)
			)
		)
		(pin "1"
		)
		(instances
			(project "jetson-orin-baseboard"
				(path ""
					(reference "#PWR0202")
					(unit 1)
				)
			)
		)
	)
	(symbol
		(lib_id "antmicroTestPoints:TP_0.75mm_SMD")
		(at 97.79 96.52 0)
		(unit 1)
		(exclude_from_sim no)
		(in_bom no)
		(on_board yes)
		(dnp no)
		(property "Reference" "TP41"
			(at 101.6 96.5199 0)
			(effects
				(font
					(size 1.27 1.27)
				)
				(justify left)
			)
		)
		(property "Value" "TP_0.75mm_SMD"
			(at 107.95 100.33 0)
			(effects
				(font
					(size 1.27 1.27)
					(thickness 0.15)
				)
				(justify left bottom)
				(hide yes)
			)
		)
		(property "Footprint" "antmicro-footprints:TP_SMD_0.75mm"
			(at 107.95 102.87 0)
			(effects
				(font
					(size 1.27 1.27)
					(thickness 0.15)
				)
				(justify left bottom)
				(hide yes)
			)
		)
		(property "Datasheet" ""
			(at 115.57 109.22 0)
			(effects
				(font
					(size 1.27 1.27)
					(thickness 0.15)
				)
				(justify left bottom)
				(hide yes)
			)
		)
		(property "Description" ""
			(at 97.79 96.52 0)
			(effects
				(font
					(size 1.27 1.27)
				)
				(hide yes)
			)
		)
		(property "MPN" ""
			(at 108.585 107.95 0)
			(effects
				(font
					(size 1.27 1.27)
					(thickness 0.15)
				)
				(justify left bottom)
				(hide yes)
			)
		)
		(property "Manufacturer" ""
			(at 108.585 102.87 0)
			(effects
				(font
					(size 1.27 1.27)
					(thickness 0.15)
				)
				(justify left bottom)
				(hide yes)
			)
		)
		(property "Author" "Antmicro"
			(at 107.95 105.41 0)
			(effects
				(font
					(size 1.27 1.27)
					(thickness 0.15)
				)
				(justify left bottom)
				(hide yes)
			)
		)
		(property "License" "Apache-2.0"
			(at 107.95 107.95 0)
			(effects
				(font
					(size 1.27 1.27)
					(thickness 0.15)
				)
				(justify left bottom)
				(hide yes)
			)
		)
		(pin "1"
		)
		(instances
			(project "jetson-orin-baseboard"
				(path ""
					(reference "TP41")
					(unit 1)
				)
			)
		)
	)
	(symbol
		(lib_id "antmicroResistors0402:R_4k7_0402")
		(at 123.19 219.71 90)
		(unit 1)
		(exclude_from_sim no)
		(in_bom yes)
		(on_board yes)
		(dnp no)
		(property "Reference" "R7"
			(at 124.46 215.9 90)
			(effects
				(font
					(size 1.27 1.27)
				)
				(justify right)
			)
		)
		(property "Value" "R_4k7_0402"
			(at 135.89 199.39 0)
			(effects
				(font
					(size 1.27 1.27)
					(thickness 0.15)
				)
				(justify left bottom)
				(hide yes)
			)
		)
		(property "Footprint" "antmicro-footprints:R_0402_1005Metric"
			(at 138.43 199.39 0)
			(effects
				(font
					(size 1.27 1.27)
					(thickness 0.15)
				)
				(justify left bottom)
				(hide yes)
			)
		)
		(property "Datasheet" "https://www.bourns.com/docs/product-datasheets/cr.pdf"
			(at 140.97 199.39 0)
			(effects
				(font
					(size 1.27 1.27)
					(thickness 0.15)
				)
				(justify left bottom)
				(hide yes)
			)
		)
		(property "Description" ""
			(at 123.19 219.71 0)
			(effects
				(font
					(size 1.27 1.27)
				)
				(hide yes)
			)
		)
		(property "Manufacturer" "Bourns"
			(at 146.05 199.39 0)
			(effects
				(font
					(size 1.27 1.27)
					(thickness 0.15)
				)
				(justify left bottom)
				(hide yes)
			)
		)
		(property "MPN" "CR0402-FX-4701GLF"
			(at 143.51 199.39 0)
			(effects
				(font
					(size 1.27 1.27)
					(thickness 0.15)
				)
				(justify left bottom)
				(hide yes)
			)
		)
		(property "Val" "4k7"
			(at 124.46 218.44 90)
			(effects
				(font
					(size 1.27 1.27)
					(thickness 0.15)
				)
				(justify right)
			)
		)
		(property "License" "Apache-2.0"
			(at 148.59 199.39 0)
			(effects
				(font
					(size 1.27 1.27)
					(thickness 0.15)
				)
				(justify left bottom)
				(hide yes)
			)
		)
		(property "Author" "Antmicro"
			(at 151.13 199.39 0)
			(effects
				(font
					(size 1.27 1.27)
					(thickness 0.15)
				)
				(justify left bottom)
				(hide yes)
			)
		)
		(property "Tolerance" "1%"
			(at 133.35 199.39 0)
			(effects
				(font
					(size 1.27 1.27)
				)
				(justify left bottom)
				(hide yes)
			)
		)
		(pin "1"
		)
		(pin "2"
		)
		(instances
			(project "jetson-orin-baseboard"
				(path ""
					(reference "R7")
					(unit 1)
				)
			)
		)
	)
	(symbol
		(lib_id "antmicroResistors0402:R_10k_0402")
		(at 44.45 77.47 270)
		(unit 1)
		(exclude_from_sim no)
		(in_bom yes)
		(on_board yes)
		(dnp no)
		(property "Reference" "R163"
			(at 45.72 78.74 90)
			(effects
				(font
					(size 1.27 1.27)
				)
				(justify left)
			)
		)
		(property "Value" "R_10k_0402"
			(at 31.75 97.79 0)
			(effects
				(font
					(size 1.27 1.27)
					(thickness 0.15)
				)
				(justify left bottom)
				(hide yes)
			)
		)
		(property "Footprint" "antmicro-footprints:R_0402_1005Metric"
			(at 29.21 97.79 0)
			(effects
				(font
					(size 1.27 1.27)
					(thickness 0.15)
				)
				(justify left bottom)
				(hide yes)
			)
		)
		(property "Datasheet" "https://www.bourns.com/docs/product-datasheets/cr.pdf"
			(at 26.67 97.79 0)
			(effects
				(font
					(size 1.27 1.27)
					(thickness 0.15)
				)
				(justify left bottom)
				(hide yes)
			)
		)
		(property "Description" ""
			(at 44.45 77.47 0)
			(effects
				(font
					(size 1.27 1.27)
				)
				(hide yes)
			)
		)
		(property "Manufacturer" "Bourns"
			(at 21.59 97.79 0)
			(effects
				(font
					(size 1.27 1.27)
					(thickness 0.15)
				)
				(justify left bottom)
				(hide yes)
			)
		)
		(property "MPN" "CR0402-FX-1002GLF"
			(at 24.13 97.79 0)
			(effects
				(font
					(size 1.27 1.27)
					(thickness 0.15)
				)
				(justify left bottom)
				(hide yes)
			)
		)
		(property "Val" "10k"
			(at 45.72 81.28 90)
			(effects
				(font
					(size 1.27 1.27)
					(thickness 0.15)
				)
				(justify left)
			)
		)
		(property "License" "Apache-2.0"
			(at 19.05 97.79 0)
			(effects
				(font
					(size 1.27 1.27)
					(thickness 0.15)
				)
				(justify left bottom)
				(hide yes)
			)
		)
		(property "Author" "Antmicro"
			(at 16.51 97.79 0)
			(effects
				(font
					(size 1.27 1.27)
					(thickness 0.15)
				)
				(justify left bottom)
				(hide yes)
			)
		)
		(property "Tolerance" "1%"
			(at 34.29 97.79 0)
			(effects
				(font
					(size 1.27 1.27)
				)
				(justify left bottom)
				(hide yes)
			)
		)
		(pin "1"
		)
		(pin "2"
		)
		(instances
			(project "jetson-orin-baseboard"
				(path ""
					(reference "R163")
					(unit 1)
				)
			)
		)
	)
	(symbol
		(lib_id "antmicroResistors0402:R_0R_0402")
		(at 40.64 60.96 180)
		(unit 1)
		(exclude_from_sim no)
		(in_bom yes)
		(on_board yes)
		(dnp no)
		(property "Reference" "R161"
			(at 40.64 60.325 0)
			(effects
				(font
					(size 1.27 1.27)
				)
				(justify right top)
			)
		)
		(property "Value" "R_0R_0402"
			(at 20.32 48.26 0)
			(effects
				(font
					(size 1.27 1.27)
					(thickness 0.15)
				)
				(justify left bottom)
				(hide yes)
			)
		)
		(property "Footprint" "antmicro-footprints:R_0402_1005Metric"
			(at 20.32 45.72 0)
			(effects
				(font
					(size 1.27 1.27)
					(thickness 0.15)
				)
				(justify left bottom)
				(hide yes)
			)
		)
		(property "Datasheet" "https://industrial.panasonic.com/cdbs/www-data/pdf/RDA0000/AOA0000C301.pdf"
			(at 20.32 43.18 0)
			(effects
				(font
					(size 1.27 1.27)
					(thickness 0.15)
				)
				(justify left bottom)
				(hide yes)
			)
		)
		(property "Description" ""
			(at 40.64 60.96 0)
			(effects
				(font
					(size 1.27 1.27)
				)
				(hide yes)
			)
		)
		(property "Manufacturer" "Panasonic"
			(at 20.32 38.1 0)
			(effects
				(font
					(size 1.27 1.27)
					(thickness 0.15)
				)
				(justify left bottom)
				(hide yes)
			)
		)
		(property "MPN" "ERJ2GE0R00X"
			(at 20.32 40.64 0)
			(effects
				(font
					(size 1.27 1.27)
					(thickness 0.15)
				)
				(justify left bottom)
				(hide yes)
			)
		)
		(property "Val" "0R"
			(at 33.02 60.325 0)
			(effects
				(font
					(size 1.27 1.27)
					(thickness 0.15)
				)
				(justify right top)
			)
		)
		(property "License" "Apache-2.0"
			(at 20.32 35.56 0)
			(effects
				(font
					(size 1.27 1.27)
					(thickness 0.15)
				)
				(justify left bottom)
				(hide yes)
			)
		)
		(property "Author" "Antmicro"
			(at 20.32 33.02 0)
			(effects
				(font
					(size 1.27 1.27)
					(thickness 0.15)
				)
				(justify left bottom)
				(hide yes)
			)
		)
		(property "Tolerance" "~"
			(at 20.32 50.8 0)
			(effects
				(font
					(size 1.27 1.27)
				)
				(justify left bottom)
				(hide yes)
			)
		)
		(property "Current" "1A"
			(at 20.32 30.48 0)
			(effects
				(font
					(size 1.27 1.27)
					(thickness 0.15)
				)
				(justify left bottom)
				(hide yes)
			)
		)
		(pin "1"
		)
		(pin "2"
		)
		(instances
			(project "jetson-orin-baseboard"
				(path ""
					(reference "R161")
					(unit 1)
				)
			)
		)
	)
	(symbol
		(lib_id "antmicropower:GND")
		(at 251.46 168.91 0)
		(unit 1)
		(exclude_from_sim no)
		(in_bom yes)
		(on_board yes)
		(dnp no)
		(property "Reference" "#PWR0166"
			(at 251.46 175.26 0)
			(effects
				(font
					(size 1.27 1.27)
				)
				(justify left bottom)
				(hide yes)
			)
		)
		(property "Value" "GND"
			(at 251.46 172.72 0)
			(effects
				(font
					(size 1.27 1.27)
					(thickness 0.15)
				)
			)
		)
		(property "Footprint" ""
			(at 260.35 176.53 0)
			(effects
				(font
					(size 1.27 1.27)
					(thickness 0.15)
				)
				(justify left bottom)
				(hide yes)
			)
		)
		(property "Datasheet" ""
			(at 260.35 181.61 0)
			(effects
				(font
					(size 1.27 1.27)
					(thickness 0.15)
				)
				(justify left bottom)
				(hide yes)
			)
		)
		(property "Description" ""
			(at 251.46 168.91 0)
			(effects
				(font
					(size 1.27 1.27)
				)
				(hide yes)
			)
		)
		(property "Author" "Antmicro"
			(at 260.35 176.53 0)
			(effects
				(font
					(size 1.27 1.27)
					(thickness 0.15)
				)
				(justify left bottom)
				(hide yes)
			)
		)
		(property "License" "Apache-2.0"
			(at 260.35 179.07 0)
			(effects
				(font
					(size 1.27 1.27)
					(thickness 0.15)
				)
				(justify left bottom)
				(hide yes)
			)
		)
		(pin "1"
		)
		(instances
			(project "jetson-orin-baseboard"
				(path ""
					(reference "#PWR0166")
					(unit 1)
				)
			)
		)
	)
	(symbol
		(lib_id "antmicroResistors0402:R_100k_0402")
		(at 66.04 255.27 90)
		(unit 1)
		(exclude_from_sim no)
		(in_bom yes)
		(on_board yes)
		(dnp no)
		(property "Reference" "R6"
			(at 67.31 251.46 90)
			(effects
				(font
					(size 1.27 1.27)
				)
				(justify right)
			)
		)
		(property "Value" "R_100k_0402"
			(at 78.74 234.95 0)
			(effects
				(font
					(size 1.27 1.27)
					(thickness 0.15)
				)
				(justify left bottom)
				(hide yes)
			)
		)
		(property "Footprint" "antmicro-footprints:R_0402_1005Metric"
			(at 81.28 234.95 0)
			(effects
				(font
					(size 1.27 1.27)
					(thickness 0.15)
				)
				(justify left bottom)
				(hide yes)
			)
		)
		(property "Datasheet" "https://www.bourns.com/docs/product-datasheets/cr.pdf"
			(at 83.82 234.95 0)
			(effects
				(font
					(size 1.27 1.27)
					(thickness 0.15)
				)
				(justify left bottom)
				(hide yes)
			)
		)
		(property "Description" ""
			(at 66.04 255.27 0)
			(effects
				(font
					(size 1.27 1.27)
				)
				(hide yes)
			)
		)
		(property "Manufacturer" "Bourns"
			(at 88.9 234.95 0)
			(effects
				(font
					(size 1.27 1.27)
					(thickness 0.15)
				)
				(justify left bottom)
				(hide yes)
			)
		)
		(property "MPN" "CR0402-FX-1003GLF"
			(at 86.36 234.95 0)
			(effects
				(font
					(size 1.27 1.27)
					(thickness 0.15)
				)
				(justify left bottom)
				(hide yes)
			)
		)
		(property "Val" "100k"
			(at 67.31 254 90)
			(effects
				(font
					(size 1.27 1.27)
					(thickness 0.15)
				)
				(justify right)
			)
		)
		(property "License" "Apache-2.0"
			(at 91.44 234.95 0)
			(effects
				(font
					(size 1.27 1.27)
					(thickness 0.15)
				)
				(justify left bottom)
				(hide yes)
			)
		)
		(property "Author" "Antmicro"
			(at 93.98 234.95 0)
			(effects
				(font
					(size 1.27 1.27)
					(thickness 0.15)
				)
				(justify left bottom)
				(hide yes)
			)
		)
		(property "Tolerance" "1%"
			(at 76.2 234.95 0)
			(effects
				(font
					(size 1.27 1.27)
				)
				(justify left bottom)
				(hide yes)
			)
		)
		(pin "1"
		)
		(pin "2"
		)
		(instances
			(project "jetson-orin-baseboard"
				(path ""
					(reference "R6")
					(unit 1)
				)
			)
		)
	)
	(symbol
		(lib_id "antmicropower:+5V")
		(at 76.2 200.66 0)
		(unit 1)
		(exclude_from_sim no)
		(in_bom yes)
		(on_board yes)
		(dnp no)
		(property "Reference" "#PWR0224"
			(at 76.2 204.47 0)
			(effects
				(font
					(size 1.27 1.27)
				)
				(justify left bottom)
				(hide yes)
			)
		)
		(property "Value" "+5V"
			(at 73.66 196.85 0)
			(effects
				(font
					(size 1.27 1.27)
					(thickness 0.15)
				)
				(justify left)
			)
		)
		(property "Footprint" ""
			(at 91.44 208.28 0)
			(effects
				(font
					(size 1.27 1.27)
					(thickness 0.15)
				)
				(justify left bottom)
				(hide yes)
			)
		)
		(property "Datasheet" ""
			(at 91.44 210.82 0)
			(effects
				(font
					(size 1.27 1.27)
					(thickness 0.15)
				)
				(justify left bottom)
				(hide yes)
			)
		)
		(property "Description" ""
			(at 76.2 200.66 0)
			(effects
				(font
					(size 1.27 1.27)
				)
				(hide yes)
			)
		)
		(property "Author" "Antmicro"
			(at 91.44 208.28 0)
			(effects
				(font
					(size 1.27 1.27)
					(thickness 0.15)
				)
				(justify left bottom)
				(hide yes)
			)
		)
		(property "License" "Apache-2.0"
			(at 91.44 210.82 0)
			(effects
				(font
					(size 1.27 1.27)
					(thickness 0.15)
				)
				(justify left bottom)
				(hide yes)
			)
		)
		(pin "1"
		)
		(instances
			(project "jetson-orin-baseboard"
				(path ""
					(reference "#PWR0224")
					(unit 1)
				)
			)
		)
	)
	(symbol
		(lib_id "antmicropower:GND")
		(at 35.56 101.6 0)
		(unit 1)
		(exclude_from_sim no)
		(in_bom yes)
		(on_board yes)
		(dnp no)
		(property "Reference" "#PWR0158"
			(at 35.56 107.95 0)
			(effects
				(font
					(size 1.27 1.27)
				)
				(justify left bottom)
				(hide yes)
			)
		)
		(property "Value" "GND"
			(at 35.56 105.41 0)
			(effects
				(font
					(size 1.27 1.27)
					(thickness 0.15)
				)
			)
		)
		(property "Footprint" ""
			(at 44.45 109.22 0)
			(effects
				(font
					(size 1.27 1.27)
					(thickness 0.15)
				)
				(justify left bottom)
				(hide yes)
			)
		)
		(property "Datasheet" ""
			(at 44.45 114.3 0)
			(effects
				(font
					(size 1.27 1.27)
					(thickness 0.15)
				)
				(justify left bottom)
				(hide yes)
			)
		)
		(property "Description" ""
			(at 35.56 101.6 0)
			(effects
				(font
					(size 1.27 1.27)
				)
				(hide yes)
			)
		)
		(property "Author" "Antmicro"
			(at 44.45 109.22 0)
			(effects
				(font
					(size 1.27 1.27)
					(thickness 0.15)
				)
				(justify left bottom)
				(hide yes)
			)
		)
		(property "License" "Apache-2.0"
			(at 44.45 111.76 0)
			(effects
				(font
					(size 1.27 1.27)
					(thickness 0.15)
				)
				(justify left bottom)
				(hide yes)
			)
		)
		(pin "1"
		)
		(instances
			(project "jetson-orin-baseboard"
				(path ""
					(reference "#PWR0158")
					(unit 1)
				)
			)
		)
	)
	(symbol
		(lib_id "antmicropower:+3V3")
		(at 175.26 200.66 0)
		(unit 1)
		(exclude_from_sim no)
		(in_bom yes)
		(on_board yes)
		(dnp no)
		(property "Reference" "#PWR0324"
			(at 175.26 204.47 0)
			(effects
				(font
					(size 1.27 1.27)
				)
				(justify left bottom)
				(hide yes)
			)
		)
		(property "Value" "+3V3"
			(at 172.085 196.85 0)
			(effects
				(font
					(size 1.27 1.27)
					(thickness 0.15)
				)
				(justify left)
			)
		)
		(property "Footprint" ""
			(at 190.5 208.28 0)
			(effects
				(font
					(size 1.27 1.27)
					(thickness 0.15)
				)
				(justify left bottom)
				(hide yes)
			)
		)
		(property "Datasheet" ""
			(at 190.5 210.82 0)
			(effects
				(font
					(size 1.27 1.27)
					(thickness 0.15)
				)
				(justify left bottom)
				(hide yes)
			)
		)
		(property "Description" ""
			(at 175.26 200.66 0)
			(effects
				(font
					(size 1.27 1.27)
				)
				(hide yes)
			)
		)
		(property "Author" "Antmicro"
			(at 190.5 203.2 0)
			(effects
				(font
					(size 1.27 1.27)
					(thickness 0.15)
				)
				(justify left bottom)
				(hide yes)
			)
		)
		(property "License" "Apache-2.0"
			(at 190.5 205.74 0)
			(effects
				(font
					(size 1.27 1.27)
					(thickness 0.15)
				)
				(justify left bottom)
				(hide yes)
			)
		)
		(pin "1"
		)
		(instances
			(project "jetson-orin-baseboard"
				(path ""
					(reference "#PWR0324")
					(unit 1)
				)
			)
		)
	)
	(symbol
		(lib_id "antmicroCapacitors0402:C_100n_0402")
		(at 185.42 234.95 90)
		(mirror x)
		(unit 1)
		(exclude_from_sim no)
		(in_bom yes)
		(on_board yes)
		(dnp no)
		(property "Reference" "C91"
			(at 187.325 236.22 90)
			(effects
				(font
					(size 1.27 1.27)
				)
				(justify right)
			)
		)
		(property "Value" "C_100n_0402"
			(at 195.58 255.27 0)
			(effects
				(font
					(size 1.27 1.27)
					(thickness 0.15)
				)
				(justify left bottom)
				(hide yes)
			)
		)
		(property "Footprint" "antmicro-footprints:C_0402_1005Metric"
			(at 198.12 255.27 0)
			(effects
				(font
					(size 1.27 1.27)
					(thickness 0.15)
				)
				(justify left bottom)
				(hide yes)
			)
		)
		(property "Datasheet" "https://www.murata.com/products/productdetail?partno=GRM155R61H104KE14%23"
			(at 200.66 255.27 0)
			(effects
				(font
					(size 1.27 1.27)
					(thickness 0.15)
				)
				(justify left bottom)
				(hide yes)
			)
		)
		(property "Description" ""
			(at 185.42 234.95 0)
			(effects
				(font
					(size 1.27 1.27)
				)
				(hide yes)
			)
		)
		(property "Manufacturer" "Murata"
			(at 205.74 255.27 0)
			(effects
				(font
					(size 1.27 1.27)
					(thickness 0.15)
				)
				(justify left bottom)
				(hide yes)
			)
		)
		(property "MPN" "GRM155R61H104KE14D"
			(at 203.2 255.27 0)
			(effects
				(font
					(size 1.27 1.27)
					(thickness 0.15)
				)
				(justify left bottom)
				(hide yes)
			)
		)
		(property "Val" "100n"
			(at 187.325 238.76 90)
			(effects
				(font
					(size 1.27 1.27)
					(thickness 0.15)
				)
				(justify right)
			)
		)
		(property "License" "Apache-2.0"
			(at 208.28 255.27 0)
			(effects
				(font
					(size 1.27 1.27)
					(thickness 0.15)
				)
				(justify left bottom)
				(hide yes)
			)
		)
		(property "Author" "Antmicro"
			(at 210.82 255.27 0)
			(effects
				(font
					(size 1.27 1.27)
					(thickness 0.15)
				)
				(justify left bottom)
				(hide yes)
			)
		)
		(property "Voltage" "50V"
			(at 213.36 255.27 0)
			(effects
				(font
					(size 1.27 1.27)
				)
				(justify left bottom)
				(hide yes)
			)
		)
		(property "Dielectric" "X5R"
			(at 215.9 255.27 0)
			(effects
				(font
					(size 1.27 1.27)
				)
				(justify left bottom)
				(hide yes)
			)
		)
		(pin "1"
		)
		(pin "2"
		)
		(instances
			(project "jetson-orin-baseboard"
				(path ""
					(reference "C91")
					(unit 1)
				)
			)
		)
	)
	(symbol
		(lib_id "antmicroLEDIndicationDiscrete:LED_G_0603_LTST-C190GKT")
		(at 246.38 167.64 90)
		(unit 1)
		(exclude_from_sim no)
		(in_bom yes)
		(on_board yes)
		(dnp no)
		(fields_autoplaced yes)
		(property "Reference" "D18"
			(at 242.57 163.83 90)
			(effects
				(font
					(size 1.27 1.27)
				)
				(justify left)
			)
		)
		(property "Value" "LED_G_0603_LTST-C190GKT"
			(at 254 144.78 0)
			(effects
				(font
					(size 1.27 1.27)
					(thickness 0.15)
				)
				(justify left bottom)
				(hide yes)
			)
		)
		(property "Footprint" "antmicro-footprints:LED_0603_1608Metric_G"
			(at 256.54 144.78 0)
			(effects
				(font
					(size 1.27 1.27)
					(thickness 0.15)
				)
				(justify left bottom)
				(hide yes)
			)
		)
		(property "Datasheet" "https://media.digikey.com/pdf/Data%20Sheets/Lite-On%20PDFs/LTST-C190GKT.pdf"
			(at 259.08 144.78 0)
			(effects
				(font
					(size 1.27 1.27)
					(thickness 0.15)
				)
				(justify left bottom)
				(hide yes)
			)
		)
		(property "Description" ""
			(at 246.38 167.64 0)
			(effects
				(font
					(size 1.27 1.27)
				)
				(hide yes)
			)
		)
		(property "MPN" "LTST-C190GKT"
			(at 261.62 144.78 0)
			(effects
				(font
					(size 1.27 1.27)
					(thickness 0.15)
				)
				(justify left bottom)
				(hide yes)
			)
		)
		(property "Manufacturer" "Lite-On"
			(at 264.16 144.78 0)
			(effects
				(font
					(size 1.27 1.27)
					(thickness 0.15)
				)
				(justify left bottom)
				(hide yes)
			)
		)
		(property "Author" "Antmicro"
			(at 266.7 144.78 0)
			(effects
				(font
					(size 1.27 1.27)
					(thickness 0.15)
				)
				(justify left bottom)
				(hide yes)
			)
		)
		(property "License" "Apache-2.0"
			(at 269.24 144.78 0)
			(effects
				(font
					(size 1.27 1.27)
					(thickness 0.15)
				)
				(justify left bottom)
				(hide yes)
			)
		)
		(property "Color" "Green"
			(at 242.57 166.37 90)
			(effects
				(font
					(size 1.27 1.27)
				)
				(justify left)
			)
		)
		(pin "1"
		)
		(pin "2"
		)
		(instances
			(project "jetson-orin-baseboard"
				(path ""
					(reference "D18")
					(unit 1)
				)
			)
		)
	)
	(symbol
		(lib_id "antmicropower:GND")
		(at 123.19 220.98 0)
		(unit 1)
		(exclude_from_sim no)
		(in_bom yes)
		(on_board yes)
		(dnp no)
		(property "Reference" "#PWR0180"
			(at 123.19 227.33 0)
			(effects
				(font
					(size 1.27 1.27)
				)
				(justify left bottom)
				(hide yes)
			)
		)
		(property "Value" "GND"
			(at 123.19 224.79 0)
			(effects
				(font
					(size 1.27 1.27)
					(thickness 0.15)
				)
			)
		)
		(property "Footprint" ""
			(at 132.08 228.6 0)
			(effects
				(font
					(size 1.27 1.27)
					(thickness 0.15)
				)
				(justify left bottom)
				(hide yes)
			)
		)
		(property "Datasheet" ""
			(at 132.08 233.68 0)
			(effects
				(font
					(size 1.27 1.27)
					(thickness 0.15)
				)
				(justify left bottom)
				(hide yes)
			)
		)
		(property "Description" ""
			(at 123.19 220.98 0)
			(effects
				(font
					(size 1.27 1.27)
				)
				(hide yes)
			)
		)
		(property "Author" "Antmicro"
			(at 132.08 228.6 0)
			(effects
				(font
					(size 1.27 1.27)
					(thickness 0.15)
				)
				(justify left bottom)
				(hide yes)
			)
		)
		(property "License" "Apache-2.0"
			(at 132.08 231.14 0)
			(effects
				(font
					(size 1.27 1.27)
					(thickness 0.15)
				)
				(justify left bottom)
				(hide yes)
			)
		)
		(pin "1"
		)
		(instances
			(project "jetson-orin-baseboard"
				(path ""
					(reference "#PWR0180")
					(unit 1)
				)
			)
		)
	)
	(symbol
		(lib_id "antmicropower:+1V8")
		(at 49.53 43.18 0)
		(unit 1)
		(exclude_from_sim no)
		(in_bom yes)
		(on_board yes)
		(dnp no)
		(property "Reference" "#PWR0303"
			(at 49.53 46.99 0)
			(effects
				(font
					(size 1.27 1.27)
				)
				(justify left bottom)
				(hide yes)
			)
		)
		(property "Value" "+1V8"
			(at 46.99 39.37 0)
			(effects
				(font
					(size 1.27 1.27)
					(thickness 0.15)
				)
				(justify left)
			)
		)
		(property "Footprint" ""
			(at 64.77 50.8 0)
			(effects
				(font
					(size 1.27 1.27)
					(thickness 0.15)
				)
				(justify left bottom)
				(hide yes)
			)
		)
		(property "Datasheet" ""
			(at 64.77 53.34 0)
			(effects
				(font
					(size 1.27 1.27)
					(thickness 0.15)
				)
				(justify left bottom)
				(hide yes)
			)
		)
		(property "Description" ""
			(at 49.53 43.18 0)
			(effects
				(font
					(size 1.27 1.27)
				)
				(hide yes)
			)
		)
		(property "Author" "Antmicro"
			(at 64.77 48.26 0)
			(effects
				(font
					(size 1.27 1.27)
					(thickness 0.15)
				)
				(justify left bottom)
				(hide yes)
			)
		)
		(property "License" "Apache-2.0"
			(at 64.77 50.8 0)
			(effects
				(font
					(size 1.27 1.27)
					(thickness 0.15)
				)
				(justify left bottom)
				(hide yes)
			)
		)
		(pin "1"
		)
		(instances
			(project "jetson-orin-baseboard"
				(path ""
					(reference "#PWR0303")
					(unit 1)
				)
			)
		)
	)
	(symbol
		(lib_id "antmicroResistorNetworksArrays:R_4x0R_0201_array")
		(at 273.05 129.54 0)
		(unit 1)
		(exclude_from_sim no)
		(in_bom yes)
		(on_board yes)
		(dnp no)
		(property "Reference" "R50"
			(at 278.13 123.825 0)
			(effects
				(font
					(size 1.27 1.27)
				)
			)
		)
		(property "Value" "R_4x0R_0201_array"
			(at 299.72 137.16 0)
			(effects
				(font
					(size 1.27 1.27)
					(thickness 0.15)
				)
				(justify left bottom)
				(hide yes)
			)
		)
		(property "Footprint" "antmicro-footprints:R_Array_4x0201_Panasonic_EXB18V"
			(at 299.72 142.24 0)
			(effects
				(font
					(size 1.27 1.27)
					(thickness 0.15)
				)
				(justify left bottom)
				(hide yes)
			)
		)
		(property "Datasheet" "http://industrial.panasonic.com/cdbs/www-data/pdf/AOC0000/AOC0000C14.pdf"
			(at 299.72 144.78 0)
			(effects
				(font
					(size 1.27 1.27)
					(thickness 0.15)
				)
				(justify left bottom)
				(hide yes)
			)
		)
		(property "Description" ""
			(at 273.05 129.54 0)
			(effects
				(font
					(size 1.27 1.27)
				)
				(hide yes)
			)
		)
		(property "MPN" "EXB-18VR000X"
			(at 299.72 147.32 0)
			(effects
				(font
					(size 1.27 1.27)
					(thickness 0.15)
				)
				(justify left bottom)
				(hide yes)
			)
		)
		(property "Manufacturer" "Panasonic"
			(at 299.72 149.86 0)
			(effects
				(font
					(size 1.27 1.27)
					(thickness 0.15)
				)
				(justify left bottom)
				(hide yes)
			)
		)
		(property "Val" "4x0R_0201"
			(at 278.13 126.365 0)
			(effects
				(font
					(size 1.27 1.27)
					(thickness 0.15)
				)
			)
		)
		(property "Author" "Antmicro"
			(at 299.72 152.4 0)
			(effects
				(font
					(size 1.27 1.27)
					(thickness 0.15)
				)
				(justify left bottom)
				(hide yes)
			)
		)
		(property "License" "Apache-2.0"
			(at 299.72 154.94 0)
			(effects
				(font
					(size 1.27 1.27)
					(thickness 0.15)
				)
				(justify left bottom)
				(hide yes)
			)
		)
		(pin "1"
		)
		(pin "2"
		)
		(pin "3"
		)
		(pin "4"
		)
		(pin "5"
		)
		(pin "6"
		)
		(pin "7"
		)
		(pin "8"
		)
		(instances
			(project "jetson-orin-baseboard"
				(path ""
					(reference "R50")
					(unit 1)
				)
			)
		)
	)
	(symbol
		(lib_id "antmicroResistors0402:R_200R_0402")
		(at 246.38 161.29 90)
		(unit 1)
		(exclude_from_sim no)
		(in_bom yes)
		(on_board yes)
		(dnp no)
		(fields_autoplaced yes)
		(property "Reference" "R132"
			(at 243.84 157.48 90)
			(effects
				(font
					(size 1.27 1.27)
				)
				(justify left)
			)
		)
		(property "Value" "R_200R_0402"
			(at 259.08 140.97 0)
			(effects
				(font
					(size 1.27 1.27)
					(thickness 0.15)
				)
				(justify left bottom)
				(hide yes)
			)
		)
		(property "Footprint" "antmicro-footprints:R_0402_1005Metric"
			(at 261.62 140.97 0)
			(effects
				(font
					(size 1.27 1.27)
					(thickness 0.15)
				)
				(justify left bottom)
				(hide yes)
			)
		)
		(property "Datasheet" "https://www.bourns.com/docs/product-datasheets/cr.pdf"
			(at 264.16 140.97 0)
			(effects
				(font
					(size 1.27 1.27)
					(thickness 0.15)
				)
				(justify left bottom)
				(hide yes)
			)
		)
		(property "Description" ""
			(at 246.38 161.29 0)
			(effects
				(font
					(size 1.27 1.27)
				)
				(hide yes)
			)
		)
		(property "Manufacturer" "Bourns"
			(at 269.24 140.97 0)
			(effects
				(font
					(size 1.27 1.27)
					(thickness 0.15)
				)
				(justify left bottom)
				(hide yes)
			)
		)
		(property "MPN" "CR0402-FX-2000GLF"
			(at 266.7 140.97 0)
			(effects
				(font
					(size 1.27 1.27)
					(thickness 0.15)
				)
				(justify left bottom)
				(hide yes)
			)
		)
		(property "Val" "200R"
			(at 243.84 160.02 90)
			(effects
				(font
					(size 1.27 1.27)
					(thickness 0.15)
				)
				(justify left)
			)
		)
		(property "License" "Apache-2.0"
			(at 271.78 140.97 0)
			(effects
				(font
					(size 1.27 1.27)
					(thickness 0.15)
				)
				(justify left bottom)
				(hide yes)
			)
		)
		(property "Author" "Antmicro"
			(at 274.32 140.97 0)
			(effects
				(font
					(size 1.27 1.27)
					(thickness 0.15)
				)
				(justify left bottom)
				(hide yes)
			)
		)
		(property "Tolerance" "1%"
			(at 256.54 140.97 0)
			(effects
				(font
					(size 1.27 1.27)
				)
				(justify left bottom)
				(hide yes)
			)
		)
		(pin "1"
		)
		(pin "2"
		)
		(instances
			(project "jetson-orin-baseboard"
				(path ""
					(reference "R132")
					(unit 1)
				)
			)
		)
	)
	(symbol
		(lib_id "antmicropower:+3V3")
		(at 66.04 200.66 0)
		(unit 1)
		(exclude_from_sim no)
		(in_bom yes)
		(on_board yes)
		(dnp no)
		(property "Reference" "#PWR0326"
			(at 66.04 204.47 0)
			(effects
				(font
					(size 1.27 1.27)
				)
				(justify left bottom)
				(hide yes)
			)
		)
		(property "Value" "+3V3"
			(at 62.865 196.85 0)
			(effects
				(font
					(size 1.27 1.27)
					(thickness 0.15)
				)
				(justify left)
			)
		)
		(property "Footprint" ""
			(at 81.28 208.28 0)
			(effects
				(font
					(size 1.27 1.27)
					(thickness 0.15)
				)
				(justify left bottom)
				(hide yes)
			)
		)
		(property "Datasheet" ""
			(at 81.28 210.82 0)
			(effects
				(font
					(size 1.27 1.27)
					(thickness 0.15)
				)
				(justify left bottom)
				(hide yes)
			)
		)
		(property "Description" ""
			(at 66.04 200.66 0)
			(effects
				(font
					(size 1.27 1.27)
				)
				(hide yes)
			)
		)
		(property "Author" "Antmicro"
			(at 81.28 203.2 0)
			(effects
				(font
					(size 1.27 1.27)
					(thickness 0.15)
				)
				(justify left bottom)
				(hide yes)
			)
		)
		(property "License" "Apache-2.0"
			(at 81.28 205.74 0)
			(effects
				(font
					(size 1.27 1.27)
					(thickness 0.15)
				)
				(justify left bottom)
				(hide yes)
			)
		)
		(pin "1"
		)
		(instances
			(project "jetson-orin-baseboard"
				(path ""
					(reference "#PWR0326")
					(unit 1)
				)
			)
		)
	)
	(symbol
		(lib_id "antmicroCapacitors0402:C_1u_0402")
		(at 271.78 161.29 90)
		(unit 1)
		(exclude_from_sim no)
		(in_bom yes)
		(on_board yes)
		(dnp no)
		(fields_autoplaced yes)
		(property "Reference" "C95"
			(at 274.32 157.4736 90)
			(effects
				(font
					(size 1.27 1.27)
				)
				(justify right)
			)
		)
		(property "Value" "C_1u_0402"
			(at 281.94 140.97 0)
			(effects
				(font
					(size 1.27 1.27)
					(thickness 0.15)
				)
				(justify left bottom)
				(hide yes)
			)
		)
		(property "Footprint" "antmicro-footprints:C_0402_1005Metric"
			(at 284.48 140.97 0)
			(effects
				(font
					(size 1.27 1.27)
					(thickness 0.15)
				)
				(justify left bottom)
				(hide yes)
			)
		)
		(property "Datasheet" "https://product.tdk.com/en/search/capacitor/ceramic/mlcc/info?part_no=C1005X6S1A105K050BC"
			(at 287.02 140.97 0)
			(effects
				(font
					(size 1.27 1.27)
					(thickness 0.15)
				)
				(justify left bottom)
				(hide yes)
			)
		)
		(property "Description" ""
			(at 271.78 161.29 0)
			(effects
				(font
					(size 1.27 1.27)
				)
				(hide yes)
			)
		)
		(property "Manufacturer" "TDK"
			(at 292.1 140.97 0)
			(effects
				(font
					(size 1.27 1.27)
					(thickness 0.15)
				)
				(justify left bottom)
				(hide yes)
			)
		)
		(property "MPN" "C1005X6S1A105K050BC"
			(at 289.56 140.97 0)
			(effects
				(font
					(size 1.27 1.27)
					(thickness 0.15)
				)
				(justify left bottom)
				(hide yes)
			)
		)
		(property "Val" "1u"
			(at 274.32 160.0136 90)
			(effects
				(font
					(size 1.27 1.27)
					(thickness 0.15)
				)
				(justify right)
			)
		)
		(property "License" "Apache-2.0"
			(at 294.64 140.97 0)
			(effects
				(font
					(size 1.27 1.27)
					(thickness 0.15)
				)
				(justify left bottom)
				(hide yes)
			)
		)
		(property "Author" "Antmicro"
			(at 297.18 140.97 0)
			(effects
				(font
					(size 1.27 1.27)
					(thickness 0.15)
				)
				(justify left bottom)
				(hide yes)
			)
		)
		(property "Voltage" ""
			(at 299.72 140.97 0)
			(effects
				(font
					(size 1.27 1.27)
				)
				(justify left bottom)
				(hide yes)
			)
		)
		(property "Dielectric" ""
			(at 302.26 140.97 0)
			(effects
				(font
					(size 1.27 1.27)
				)
				(justify left bottom)
				(hide yes)
			)
		)
		(pin "1"
		)
		(pin "2"
		)
		(instances
			(project "jetson-orin-baseboard"
				(path ""
					(reference "C95")
					(unit 1)
				)
			)
		)
	)
	(symbol
		(lib_id "antmicropower:GND")
		(at 328.93 168.91 0)
		(unit 1)
		(exclude_from_sim no)
		(in_bom yes)
		(on_board yes)
		(dnp no)
		(property "Reference" "#PWR0208"
			(at 328.93 175.26 0)
			(effects
				(font
					(size 1.27 1.27)
				)
				(justify left bottom)
				(hide yes)
			)
		)
		(property "Value" "GND"
			(at 328.93 172.72 0)
			(effects
				(font
					(size 1.27 1.27)
					(thickness 0.15)
				)
			)
		)
		(property "Footprint" ""
			(at 337.82 176.53 0)
			(effects
				(font
					(size 1.27 1.27)
					(thickness 0.15)
				)
				(justify left bottom)
				(hide yes)
			)
		)
		(property "Datasheet" ""
			(at 337.82 181.61 0)
			(effects
				(font
					(size 1.27 1.27)
					(thickness 0.15)
				)
				(justify left bottom)
				(hide yes)
			)
		)
		(property "Description" ""
			(at 328.93 168.91 0)
			(effects
				(font
					(size 1.27 1.27)
				)
				(hide yes)
			)
		)
		(property "Author" "Antmicro"
			(at 337.82 176.53 0)
			(effects
				(font
					(size 1.27 1.27)
					(thickness 0.15)
				)
				(justify left bottom)
				(hide yes)
			)
		)
		(property "License" "Apache-2.0"
			(at 337.82 179.07 0)
			(effects
				(font
					(size 1.27 1.27)
					(thickness 0.15)
				)
				(justify left bottom)
				(hide yes)
			)
		)
		(pin "1"
		)
		(instances
			(project "jetson-orin-baseboard"
				(path ""
					(reference "#PWR0208")
					(unit 1)
				)
			)
		)
	)
	(symbol
		(lib_id "antmicroResistors0402:R_10k_0402")
		(at 195.58 203.2 270)
		(unit 1)
		(exclude_from_sim no)
		(in_bom yes)
		(on_board yes)
		(dnp no)
		(property "Reference" "R67"
			(at 196.85 204.47 90)
			(effects
				(font
					(size 1.27 1.27)
				)
				(justify left)
			)
		)
		(property "Value" "R_10k_0402"
			(at 182.88 223.52 0)
			(effects
				(font
					(size 1.27 1.27)
					(thickness 0.15)
				)
				(justify left bottom)
				(hide yes)
			)
		)
		(property "Footprint" "antmicro-footprints:R_0402_1005Metric"
			(at 180.34 223.52 0)
			(effects
				(font
					(size 1.27 1.27)
					(thickness 0.15)
				)
				(justify left bottom)
				(hide yes)
			)
		)
		(property "Datasheet" "https://www.bourns.com/docs/product-datasheets/cr.pdf"
			(at 177.8 223.52 0)
			(effects
				(font
					(size 1.27 1.27)
					(thickness 0.15)
				)
				(justify left bottom)
				(hide yes)
			)
		)
		(property "Description" ""
			(at 195.58 203.2 0)
			(effects
				(font
					(size 1.27 1.27)
				)
				(hide yes)
			)
		)
		(property "Manufacturer" "Bourns"
			(at 172.72 223.52 0)
			(effects
				(font
					(size 1.27 1.27)
					(thickness 0.15)
				)
				(justify left bottom)
				(hide yes)
			)
		)
		(property "MPN" "CR0402-FX-1002GLF"
			(at 175.26 223.52 0)
			(effects
				(font
					(size 1.27 1.27)
					(thickness 0.15)
				)
				(justify left bottom)
				(hide yes)
			)
		)
		(property "Val" "10k"
			(at 196.85 207.01 90)
			(effects
				(font
					(size 1.27 1.27)
					(thickness 0.15)
				)
				(justify left)
			)
		)
		(property "License" "Apache-2.0"
			(at 170.18 223.52 0)
			(effects
				(font
					(size 1.27 1.27)
					(thickness 0.15)
				)
				(justify left bottom)
				(hide yes)
			)
		)
		(property "Author" "Antmicro"
			(at 167.64 223.52 0)
			(effects
				(font
					(size 1.27 1.27)
					(thickness 0.15)
				)
				(justify left bottom)
				(hide yes)
			)
		)
		(property "Tolerance" "1%"
			(at 185.42 223.52 0)
			(effects
				(font
					(size 1.27 1.27)
				)
				(justify left bottom)
				(hide yes)
			)
		)
		(pin "1"
		)
		(pin "2"
		)
		(instances
			(project "jetson-orin-baseboard"
				(path ""
					(reference "R67")
					(unit 1)
				)
			)
		)
	)
	(symbol
		(lib_id "antmicroCapacitors0402:C_100n_0402")
		(at 334.01 233.68 270)
		(mirror x)
		(unit 1)
		(exclude_from_sim no)
		(in_bom yes)
		(on_board yes)
		(dnp no)
		(property "Reference" "C97"
			(at 332.105 229.87 90)
			(effects
				(font
					(size 1.27 1.27)
				)
				(justify right)
			)
		)
		(property "Value" "C_100n_0402"
			(at 323.85 213.36 0)
			(effects
				(font
					(size 1.27 1.27)
					(thickness 0.15)
				)
				(justify left bottom)
				(hide yes)
			)
		)
		(property "Footprint" "antmicro-footprints:C_0402_1005Metric"
			(at 321.31 213.36 0)
			(effects
				(font
					(size 1.27 1.27)
					(thickness 0.15)
				)
				(justify left bottom)
				(hide yes)
			)
		)
		(property "Datasheet" "https://www.murata.com/products/productdetail?partno=GRM155R61H104KE14%23"
			(at 318.77 213.36 0)
			(effects
				(font
					(size 1.27 1.27)
					(thickness 0.15)
				)
				(justify left bottom)
				(hide yes)
			)
		)
		(property "Description" ""
			(at 334.01 233.68 0)
			(effects
				(font
					(size 1.27 1.27)
				)
				(hide yes)
			)
		)
		(property "Manufacturer" "Murata"
			(at 313.69 213.36 0)
			(effects
				(font
					(size 1.27 1.27)
					(thickness 0.15)
				)
				(justify left bottom)
				(hide yes)
			)
		)
		(property "MPN" "GRM155R61H104KE14D"
			(at 316.23 213.36 0)
			(effects
				(font
					(size 1.27 1.27)
					(thickness 0.15)
				)
				(justify left bottom)
				(hide yes)
			)
		)
		(property "Val" "100n"
			(at 332.105 232.41 90)
			(effects
				(font
					(size 1.27 1.27)
					(thickness 0.15)
				)
				(justify right)
			)
		)
		(property "License" "Apache-2.0"
			(at 311.15 213.36 0)
			(effects
				(font
					(size 1.27 1.27)
					(thickness 0.15)
				)
				(justify left bottom)
				(hide yes)
			)
		)
		(property "Author" "Antmicro"
			(at 308.61 213.36 0)
			(effects
				(font
					(size 1.27 1.27)
					(thickness 0.15)
				)
				(justify left bottom)
				(hide yes)
			)
		)
		(property "Voltage" "50V"
			(at 306.07 213.36 0)
			(effects
				(font
					(size 1.27 1.27)
				)
				(justify left bottom)
				(hide yes)
			)
		)
		(property "Dielectric" "X5R"
			(at 303.53 213.36 0)
			(effects
				(font
					(size 1.27 1.27)
				)
				(justify left bottom)
				(hide yes)
			)
		)
		(pin "1"
		)
		(pin "2"
		)
		(instances
			(project "jetson-orin-baseboard"
				(path ""
					(reference "C97")
					(unit 1)
				)
			)
		)
	)
	(symbol
		(lib_id "antmicroResistors0402:R_0R_0402")
		(at 26.67 135.89 90)
		(unit 1)
		(exclude_from_sim no)
		(in_bom yes)
		(on_board yes)
		(dnp no)
		(property "Reference" "R166"
			(at 25.4 132.08 90)
			(effects
				(font
					(size 1.27 1.27)
				)
				(justify left)
			)
		)
		(property "Value" "R_0R_0402"
			(at 39.37 115.57 0)
			(effects
				(font
					(size 1.27 1.27)
					(thickness 0.15)
				)
				(justify left bottom)
				(hide yes)
			)
		)
		(property "Footprint" "antmicro-footprints:R_0402_1005Metric"
			(at 41.91 115.57 0)
			(effects
				(font
					(size 1.27 1.27)
					(thickness 0.15)
				)
				(justify left bottom)
				(hide yes)
			)
		)
		(property "Datasheet" "https://industrial.panasonic.com/cdbs/www-data/pdf/RDA0000/AOA0000C301.pdf"
			(at 44.45 115.57 0)
			(effects
				(font
					(size 1.27 1.27)
					(thickness 0.15)
				)
				(justify left bottom)
				(hide yes)
			)
		)
		(property "Description" ""
			(at 26.67 135.89 0)
			(effects
				(font
					(size 1.27 1.27)
				)
				(hide yes)
			)
		)
		(property "Manufacturer" "Panasonic"
			(at 49.53 115.57 0)
			(effects
				(font
					(size 1.27 1.27)
					(thickness 0.15)
				)
				(justify left bottom)
				(hide yes)
			)
		)
		(property "MPN" "ERJ2GE0R00X"
			(at 46.99 115.57 0)
			(effects
				(font
					(size 1.27 1.27)
					(thickness 0.15)
				)
				(justify left bottom)
				(hide yes)
			)
		)
		(property "Val" "0R"
			(at 25.4 134.62 90)
			(effects
				(font
					(size 1.27 1.27)
					(thickness 0.15)
				)
				(justify left)
			)
		)
		(property "License" "Apache-2.0"
			(at 52.07 115.57 0)
			(effects
				(font
					(size 1.27 1.27)
					(thickness 0.15)
				)
				(justify left bottom)
				(hide yes)
			)
		)
		(property "Author" "Antmicro"
			(at 54.61 115.57 0)
			(effects
				(font
					(size 1.27 1.27)
					(thickness 0.15)
				)
				(justify left bottom)
				(hide yes)
			)
		)
		(property "Tolerance" "~"
			(at 36.83 115.57 0)
			(effects
				(font
					(size 1.27 1.27)
				)
				(justify left bottom)
				(hide yes)
			)
		)
		(property "Current" "1A"
			(at 57.15 115.57 0)
			(effects
				(font
					(size 1.27 1.27)
					(thickness 0.15)
				)
				(justify left bottom)
				(hide yes)
			)
		)
		(pin "1"
		)
		(pin "2"
		)
		(instances
			(project "jetson-orin-baseboard"
				(path ""
					(reference "R166")
					(unit 1)
				)
			)
		)
	)
	(symbol
		(lib_id "antmicroLogicTranslatorsLevelShifters:NTS0102_XSON")
		(at 342.9 209.55 0)
		(unit 1)
		(exclude_from_sim no)
		(in_bom yes)
		(on_board yes)
		(dnp no)
		(property "Reference" "U31"
			(at 353.06 203.2 0)
			(effects
				(font
					(size 1.27 1.27)
				)
			)
		)
		(property "Value" "NTS0102_XSON"
			(at 378.46 217.17 0)
			(effects
				(font
					(size 1.27 1.27)
					(thickness 0.15)
				)
				(justify left bottom)
				(hide yes)
			)
		)
		(property "Footprint" "antmicro-footprints:XSON-8_1x1.95mm_P0.5mm"
			(at 378.46 219.71 0)
			(effects
				(font
					(size 1.27 1.27)
					(thickness 0.15)
				)
				(justify left bottom)
				(hide yes)
			)
		)
		(property "Datasheet" "http://www.farnell.com/datasheets/1760723.pdf"
			(at 378.46 222.25 0)
			(effects
				(font
					(size 1.27 1.27)
					(thickness 0.15)
				)
				(justify left bottom)
				(hide yes)
			)
		)
		(property "Description" ""
			(at 342.9 209.55 0)
			(effects
				(font
					(size 1.27 1.27)
				)
				(hide yes)
			)
		)
		(property "MPN" "NTS0102GT"
			(at 353.06 205.74 0)
			(effects
				(font
					(size 1.27 1.27)
					(thickness 0.15)
				)
			)
		)
		(property "Manufacturer" "NXP"
			(at 378.46 224.79 0)
			(effects
				(font
					(size 1.27 1.27)
					(thickness 0.15)
				)
				(justify left bottom)
				(hide yes)
			)
		)
		(property "Author" "Antmicro"
			(at 378.46 227.33 0)
			(effects
				(font
					(size 1.27 1.27)
					(thickness 0.15)
				)
				(justify left bottom)
				(hide yes)
			)
		)
		(property "License" "Apache-2.0"
			(at 378.46 229.87 0)
			(effects
				(font
					(size 1.27 1.27)
					(thickness 0.15)
				)
				(justify left bottom)
				(hide yes)
			)
		)
		(pin "1"
		)
		(pin "2"
		)
		(pin "3"
		)
		(pin "4"
		)
		(pin "5"
		)
		(pin "6"
		)
		(pin "7"
		)
		(pin "8"
		)
		(instances
			(project "jetson-orin-baseboard"
				(path ""
					(reference "U31")
					(unit 1)
				)
			)
		)
	)
	(symbol
		(lib_id "antmicropower:+3V3")
		(at 372.11 226.06 0)
		(unit 1)
		(exclude_from_sim no)
		(in_bom yes)
		(on_board yes)
		(dnp no)
		(property "Reference" "#PWR0183"
			(at 372.11 229.87 0)
			(effects
				(font
					(size 1.27 1.27)
				)
				(justify left bottom)
				(hide yes)
			)
		)
		(property "Value" "+3V3"
			(at 368.935 222.25 0)
			(effects
				(font
					(size 1.27 1.27)
					(thickness 0.15)
				)
				(justify left)
			)
		)
		(property "Footprint" ""
			(at 387.35 233.68 0)
			(effects
				(font
					(size 1.27 1.27)
					(thickness 0.15)
				)
				(justify left bottom)
				(hide yes)
			)
		)
		(property "Datasheet" ""
			(at 387.35 236.22 0)
			(effects
				(font
					(size 1.27 1.27)
					(thickness 0.15)
				)
				(justify left bottom)
				(hide yes)
			)
		)
		(property "Description" ""
			(at 372.11 226.06 0)
			(effects
				(font
					(size 1.27 1.27)
				)
				(hide yes)
			)
		)
		(property "Author" "Antmicro"
			(at 387.35 228.6 0)
			(effects
				(font
					(size 1.27 1.27)
					(thickness 0.15)
				)
				(justify left bottom)
				(hide yes)
			)
		)
		(property "License" "Apache-2.0"
			(at 387.35 231.14 0)
			(effects
				(font
					(size 1.27 1.27)
					(thickness 0.15)
				)
				(justify left bottom)
				(hide yes)
			)
		)
		(pin "1"
		)
		(instances
			(project "jetson-orin-baseboard"
				(path ""
					(reference "#PWR0183")
					(unit 1)
				)
			)
		)
	)
	(symbol
		(lib_id "antmicropower:GND")
		(at 232.41 254 0)
		(unit 1)
		(exclude_from_sim no)
		(in_bom yes)
		(on_board yes)
		(dnp no)
		(property "Reference" "#PWR0364"
			(at 232.41 260.35 0)
			(effects
				(font
					(size 1.27 1.27)
				)
				(justify left bottom)
				(hide yes)
			)
		)
		(property "Value" "GND"
			(at 232.41 257.81 0)
			(effects
				(font
					(size 1.27 1.27)
					(thickness 0.15)
				)
			)
		)
		(property "Footprint" ""
			(at 241.3 261.62 0)
			(effects
				(font
					(size 1.27 1.27)
					(thickness 0.15)
				)
				(justify left bottom)
				(hide yes)
			)
		)
		(property "Datasheet" ""
			(at 241.3 266.7 0)
			(effects
				(font
					(size 1.27 1.27)
					(thickness 0.15)
				)
				(justify left bottom)
				(hide yes)
			)
		)
		(property "Description" ""
			(at 232.41 254 0)
			(effects
				(font
					(size 1.27 1.27)
				)
				(hide yes)
			)
		)
		(property "Author" "Antmicro"
			(at 241.3 261.62 0)
			(effects
				(font
					(size 1.27 1.27)
					(thickness 0.15)
				)
				(justify left bottom)
				(hide yes)
			)
		)
		(property "License" "Apache-2.0"
			(at 241.3 264.16 0)
			(effects
				(font
					(size 1.27 1.27)
					(thickness 0.15)
				)
				(justify left bottom)
				(hide yes)
			)
		)
		(pin "1"
		)
		(instances
			(project "jetson-orin-baseboard"
				(path ""
					(reference "#PWR0364")
					(unit 1)
				)
			)
		)
	)
	(symbol
		(lib_id "antmicroTestPoints:TP_0.75mm_SMD")
		(at 97.79 88.9 0)
		(unit 1)
		(exclude_from_sim no)
		(in_bom no)
		(on_board yes)
		(dnp no)
		(property "Reference" "TP39"
			(at 101.6 88.8999 0)
			(effects
				(font
					(size 1.27 1.27)
				)
				(justify left)
			)
		)
		(property "Value" "TP_0.75mm_SMD"
			(at 107.95 92.71 0)
			(effects
				(font
					(size 1.27 1.27)
					(thickness 0.15)
				)
				(justify left bottom)
				(hide yes)
			)
		)
		(property "Footprint" "antmicro-footprints:TP_SMD_0.75mm"
			(at 107.95 95.25 0)
			(effects
				(font
					(size 1.27 1.27)
					(thickness 0.15)
				)
				(justify left bottom)
				(hide yes)
			)
		)
		(property "Datasheet" ""
			(at 115.57 101.6 0)
			(effects
				(font
					(size 1.27 1.27)
					(thickness 0.15)
				)
				(justify left bottom)
				(hide yes)
			)
		)
		(property "Description" ""
			(at 97.79 88.9 0)
			(effects
				(font
					(size 1.27 1.27)
				)
				(hide yes)
			)
		)
		(property "MPN" ""
			(at 108.585 100.33 0)
			(effects
				(font
					(size 1.27 1.27)
					(thickness 0.15)
				)
				(justify left bottom)
				(hide yes)
			)
		)
		(property "Manufacturer" ""
			(at 108.585 95.25 0)
			(effects
				(font
					(size 1.27 1.27)
					(thickness 0.15)
				)
				(justify left bottom)
				(hide yes)
			)
		)
		(property "Author" "Antmicro"
			(at 107.95 97.79 0)
			(effects
				(font
					(size 1.27 1.27)
					(thickness 0.15)
				)
				(justify left bottom)
				(hide yes)
			)
		)
		(property "License" "Apache-2.0"
			(at 107.95 100.33 0)
			(effects
				(font
					(size 1.27 1.27)
					(thickness 0.15)
				)
				(justify left bottom)
				(hide yes)
			)
		)
		(pin "1"
		)
		(instances
			(project "jetson-orin-baseboard"
				(path ""
					(reference "TP39")
					(unit 1)
				)
			)
		)
	)
	(symbol
		(lib_id "antmicroResistors0402:R_200R_0402")
		(at 323.85 161.29 90)
		(unit 1)
		(exclude_from_sim no)
		(in_bom yes)
		(on_board yes)
		(dnp no)
		(fields_autoplaced yes)
		(property "Reference" "R133"
			(at 321.31 157.48 90)
			(effects
				(font
					(size 1.27 1.27)
				)
				(justify left)
			)
		)
		(property "Value" "R_200R_0402"
			(at 336.55 140.97 0)
			(effects
				(font
					(size 1.27 1.27)
					(thickness 0.15)
				)
				(justify left bottom)
				(hide yes)
			)
		)
		(property "Footprint" "antmicro-footprints:R_0402_1005Metric"
			(at 339.09 140.97 0)
			(effects
				(font
					(size 1.27 1.27)
					(thickness 0.15)
				)
				(justify left bottom)
				(hide yes)
			)
		)
		(property "Datasheet" "https://www.bourns.com/docs/product-datasheets/cr.pdf"
			(at 341.63 140.97 0)
			(effects
				(font
					(size 1.27 1.27)
					(thickness 0.15)
				)
				(justify left bottom)
				(hide yes)
			)
		)
		(property "Description" ""
			(at 323.85 161.29 0)
			(effects
				(font
					(size 1.27 1.27)
				)
				(hide yes)
			)
		)
		(property "Manufacturer" "Bourns"
			(at 346.71 140.97 0)
			(effects
				(font
					(size 1.27 1.27)
					(thickness 0.15)
				)
				(justify left bottom)
				(hide yes)
			)
		)
		(property "MPN" "CR0402-FX-2000GLF"
			(at 344.17 140.97 0)
			(effects
				(font
					(size 1.27 1.27)
					(thickness 0.15)
				)
				(justify left bottom)
				(hide yes)
			)
		)
		(property "Val" "200R"
			(at 321.31 160.02 90)
			(effects
				(font
					(size 1.27 1.27)
					(thickness 0.15)
				)
				(justify left)
			)
		)
		(property "License" "Apache-2.0"
			(at 349.25 140.97 0)
			(effects
				(font
					(size 1.27 1.27)
					(thickness 0.15)
				)
				(justify left bottom)
				(hide yes)
			)
		)
		(property "Author" "Antmicro"
			(at 351.79 140.97 0)
			(effects
				(font
					(size 1.27 1.27)
					(thickness 0.15)
				)
				(justify left bottom)
				(hide yes)
			)
		)
		(property "Tolerance" "1%"
			(at 334.01 140.97 0)
			(effects
				(font
					(size 1.27 1.27)
				)
				(justify left bottom)
				(hide yes)
			)
		)
		(pin "1"
		)
		(pin "2"
		)
		(instances
			(project "jetson-orin-baseboard"
				(path ""
					(reference "R133")
					(unit 1)
				)
			)
		)
	)
	(symbol
		(lib_id "antmicropower:+1V8")
		(at 44.45 74.93 0)
		(unit 1)
		(exclude_from_sim no)
		(in_bom yes)
		(on_board yes)
		(dnp no)
		(property "Reference" "#PWR0156"
			(at 44.45 78.74 0)
			(effects
				(font
					(size 1.27 1.27)
				)
				(justify left bottom)
				(hide yes)
			)
		)
		(property "Value" "+1V8"
			(at 41.275 71.12 0)
			(effects
				(font
					(size 1.27 1.27)
					(thickness 0.15)
				)
				(justify left)
			)
		)
		(property "Footprint" ""
			(at 59.69 82.55 0)
			(effects
				(font
					(size 1.27 1.27)
					(thickness 0.15)
				)
				(justify left bottom)
				(hide yes)
			)
		)
		(property "Datasheet" ""
			(at 59.69 85.09 0)
			(effects
				(font
					(size 1.27 1.27)
					(thickness 0.15)
				)
				(justify left bottom)
				(hide yes)
			)
		)
		(property "Description" ""
			(at 44.45 74.93 0)
			(effects
				(font
					(size 1.27 1.27)
				)
				(hide yes)
			)
		)
		(property "Author" "Antmicro"
			(at 59.69 80.01 0)
			(effects
				(font
					(size 1.27 1.27)
					(thickness 0.15)
				)
				(justify left bottom)
				(hide yes)
			)
		)
		(property "License" "Apache-2.0"
			(at 59.69 82.55 0)
			(effects
				(font
					(size 1.27 1.27)
					(thickness 0.15)
				)
				(justify left bottom)
				(hide yes)
			)
		)
		(pin "1"
		)
		(instances
			(project "jetson-orin-baseboard"
				(path ""
					(reference "#PWR0156")
					(unit 1)
				)
			)
		)
	)
	(symbol
		(lib_id "antmicroFCCConnectors:Conn_FFC_WE_68715014522")
		(at 287.02 33.02 0)
		(unit 1)
		(exclude_from_sim no)
		(in_bom yes)
		(on_board yes)
		(dnp no)
		(fields_autoplaced yes)
		(property "Reference" "J7"
			(at 295.91 97.155 0)
			(effects
				(font
					(size 1.27 1.27)
				)
				(justify left)
			)
		)
		(property "Value" "Conn_FFC_WE_68715014522"
			(at 306.07 40.64 0)
			(effects
				(font
					(size 1.27 1.27)
					(thickness 0.15)
				)
				(justify left bottom)
				(hide yes)
			)
		)
		(property "Footprint" "antmicro-footprints:Conn_FFC_WE_68715014x22"
			(at 306.07 43.18 0)
			(effects
				(font
					(size 1.27 1.27)
					(thickness 0.15)
				)
				(justify left bottom)
				(hide yes)
			)
		)
		(property "Datasheet" "https://www.we-online.com/components/products/datasheet/68715014522.pdf"
			(at 306.07 45.72 0)
			(effects
				(font
					(size 1.27 1.27)
					(thickness 0.15)
				)
				(justify left bottom)
				(hide yes)
			)
		)
		(property "Description" ""
			(at 287.02 33.02 0)
			(effects
				(font
					(size 1.27 1.27)
				)
				(hide yes)
			)
		)
		(property "MPN" "68715014522"
			(at 295.91 99.695 0)
			(effects
				(font
					(size 1.27 1.27)
					(thickness 0.15)
				)
				(justify left)
			)
		)
		(property "Manufacturer" "Würth Elektronik"
			(at 306.07 50.8 0)
			(effects
				(font
					(size 1.27 1.27)
					(thickness 0.15)
				)
				(justify left bottom)
				(hide yes)
			)
		)
		(property "Author" "Antmicro"
			(at 306.07 53.34 0)
			(effects
				(font
					(size 1.27 1.27)
					(thickness 0.15)
				)
				(justify left bottom)
				(hide yes)
			)
		)
		(property "License" "Apache-2.0"
			(at 306.07 55.88 0)
			(effects
				(font
					(size 1.27 1.27)
					(thickness 0.15)
				)
				(justify left bottom)
				(hide yes)
			)
		)
		(pin "1"
		)
		(pin "10"
		)
		(pin "11"
		)
		(pin "12"
		)
		(pin "13"
		)
		(pin "14"
		)
		(pin "15"
		)
		(pin "16"
		)
		(pin "17"
		)
		(pin "18"
		)
		(pin "19"
		)
		(pin "2"
		)
		(pin "20"
		)
		(pin "21"
		)
		(pin "22"
		)
		(pin "23"
		)
		(pin "24"
		)
		(pin "25"
		)
		(pin "26"
		)
		(pin "27"
		)
		(pin "28"
		)
		(pin "29"
		)
		(pin "3"
		)
		(pin "30"
		)
		(pin "31"
		)
		(pin "32"
		)
		(pin "33"
		)
		(pin "34"
		)
		(pin "35"
		)
		(pin "36"
		)
		(pin "37"
		)
		(pin "38"
		)
		(pin "39"
		)
		(pin "4"
		)
		(pin "40"
		)
		(pin "41"
		)
		(pin "42"
		)
		(pin "43"
		)
		(pin "44"
		)
		(pin "45"
		)
		(pin "46"
		)
		(pin "47"
		)
		(pin "48"
		)
		(pin "49"
		)
		(pin "5"
		)
		(pin "50"
		)
		(pin "6"
		)
		(pin "7"
		)
		(pin "8"
		)
		(pin "9"
		)
		(pin "MP2"
		)
		(pin "MP1"
		)
		(instances
			(project "jetson-orin-baseboard"
				(path ""
					(reference "J7")
					(unit 1)
				)
			)
		)
	)
	(symbol
		(lib_id "antmicropower:GND")
		(at 109.22 254 0)
		(unit 1)
		(exclude_from_sim no)
		(in_bom yes)
		(on_board yes)
		(dnp no)
		(property "Reference" "#PWR0193"
			(at 109.22 260.35 0)
			(effects
				(font
					(size 1.27 1.27)
				)
				(justify left bottom)
				(hide yes)
			)
		)
		(property "Value" "GND"
			(at 109.22 257.81 0)
			(effects
				(font
					(size 1.27 1.27)
					(thickness 0.15)
				)
			)
		)
		(property "Footprint" ""
			(at 118.11 261.62 0)
			(effects
				(font
					(size 1.27 1.27)
					(thickness 0.15)
				)
				(justify left bottom)
				(hide yes)
			)
		)
		(property "Datasheet" ""
			(at 118.11 266.7 0)
			(effects
				(font
					(size 1.27 1.27)
					(thickness 0.15)
				)
				(justify left bottom)
				(hide yes)
			)
		)
		(property "Description" ""
			(at 109.22 254 0)
			(effects
				(font
					(size 1.27 1.27)
				)
				(hide yes)
			)
		)
		(property "Author" "Antmicro"
			(at 118.11 261.62 0)
			(effects
				(font
					(size 1.27 1.27)
					(thickness 0.15)
				)
				(justify left bottom)
				(hide yes)
			)
		)
		(property "License" "Apache-2.0"
			(at 118.11 264.16 0)
			(effects
				(font
					(size 1.27 1.27)
					(thickness 0.15)
				)
				(justify left bottom)
				(hide yes)
			)
		)
		(pin "1"
		)
		(instances
			(project "jetson-orin-baseboard"
				(path ""
					(reference "#PWR0193")
					(unit 1)
				)
			)
		)
	)
	(symbol
		(lib_id "antmicropower:GND")
		(at 185.42 241.3 0)
		(unit 1)
		(exclude_from_sim no)
		(in_bom yes)
		(on_board yes)
		(dnp no)
		(property "Reference" "#PWR0359"
			(at 185.42 247.65 0)
			(effects
				(font
					(size 1.27 1.27)
				)
				(justify left bottom)
				(hide yes)
			)
		)
		(property "Value" "GND"
			(at 185.42 245.11 0)
			(effects
				(font
					(size 1.27 1.27)
					(thickness 0.15)
				)
			)
		)
		(property "Footprint" ""
			(at 194.31 248.92 0)
			(effects
				(font
					(size 1.27 1.27)
					(thickness 0.15)
				)
				(justify left bottom)
				(hide yes)
			)
		)
		(property "Datasheet" ""
			(at 194.31 254 0)
			(effects
				(font
					(size 1.27 1.27)
					(thickness 0.15)
				)
				(justify left bottom)
				(hide yes)
			)
		)
		(property "Description" ""
			(at 185.42 241.3 0)
			(effects
				(font
					(size 1.27 1.27)
				)
				(hide yes)
			)
		)
		(property "Author" "Antmicro"
			(at 194.31 248.92 0)
			(effects
				(font
					(size 1.27 1.27)
					(thickness 0.15)
				)
				(justify left bottom)
				(hide yes)
			)
		)
		(property "License" "Apache-2.0"
			(at 194.31 251.46 0)
			(effects
				(font
					(size 1.27 1.27)
					(thickness 0.15)
				)
				(justify left bottom)
				(hide yes)
			)
		)
		(pin "1"
		)
		(instances
			(project "jetson-orin-baseboard"
				(path ""
					(reference "#PWR0359")
					(unit 1)
				)
			)
		)
	)
	(symbol
		(lib_id "antmicropower:GND")
		(at 49.53 52.07 0)
		(unit 1)
		(exclude_from_sim no)
		(in_bom yes)
		(on_board yes)
		(dnp no)
		(property "Reference" "#PWR0155"
			(at 49.53 58.42 0)
			(effects
				(font
					(size 1.27 1.27)
				)
				(justify left bottom)
				(hide yes)
			)
		)
		(property "Value" "GND"
			(at 49.53 55.88 0)
			(effects
				(font
					(size 1.27 1.27)
					(thickness 0.15)
				)
			)
		)
		(property "Footprint" ""
			(at 58.42 59.69 0)
			(effects
				(font
					(size 1.27 1.27)
					(thickness 0.15)
				)
				(justify left bottom)
				(hide yes)
			)
		)
		(property "Datasheet" ""
			(at 58.42 64.77 0)
			(effects
				(font
					(size 1.27 1.27)
					(thickness 0.15)
				)
				(justify left bottom)
				(hide yes)
			)
		)
		(property "Description" ""
			(at 49.53 52.07 0)
			(effects
				(font
					(size 1.27 1.27)
				)
				(hide yes)
			)
		)
		(property "Author" "Antmicro"
			(at 58.42 59.69 0)
			(effects
				(font
					(size 1.27 1.27)
					(thickness 0.15)
				)
				(justify left bottom)
				(hide yes)
			)
		)
		(property "License" "Apache-2.0"
			(at 58.42 62.23 0)
			(effects
				(font
					(size 1.27 1.27)
					(thickness 0.15)
				)
				(justify left bottom)
				(hide yes)
			)
		)
		(pin "1"
		)
		(instances
			(project "jetson-orin-baseboard"
				(path ""
					(reference "#PWR0155")
					(unit 1)
				)
			)
		)
	)
	(symbol
		(lib_id "antmicroCapacitors0402:C_100n_0402")
		(at 76.2 203.2 90)
		(mirror x)
		(unit 1)
		(exclude_from_sim no)
		(in_bom yes)
		(on_board yes)
		(dnp no)
		(property "Reference" "C42"
			(at 78.105 204.47 90)
			(effects
				(font
					(size 1.27 1.27)
				)
				(justify right)
			)
		)
		(property "Value" "C_100n_0402"
			(at 86.36 223.52 0)
			(effects
				(font
					(size 1.27 1.27)
					(thickness 0.15)
				)
				(justify left bottom)
				(hide yes)
			)
		)
		(property "Footprint" "antmicro-footprints:C_0402_1005Metric"
			(at 88.9 223.52 0)
			(effects
				(font
					(size 1.27 1.27)
					(thickness 0.15)
				)
				(justify left bottom)
				(hide yes)
			)
		)
		(property "Datasheet" "https://www.murata.com/products/productdetail?partno=GRM155R61H104KE14%23"
			(at 91.44 223.52 0)
			(effects
				(font
					(size 1.27 1.27)
					(thickness 0.15)
				)
				(justify left bottom)
				(hide yes)
			)
		)
		(property "Description" ""
			(at 76.2 203.2 0)
			(effects
				(font
					(size 1.27 1.27)
				)
				(hide yes)
			)
		)
		(property "Manufacturer" "Murata"
			(at 96.52 223.52 0)
			(effects
				(font
					(size 1.27 1.27)
					(thickness 0.15)
				)
				(justify left bottom)
				(hide yes)
			)
		)
		(property "MPN" "GRM155R61H104KE14D"
			(at 93.98 223.52 0)
			(effects
				(font
					(size 1.27 1.27)
					(thickness 0.15)
				)
				(justify left bottom)
				(hide yes)
			)
		)
		(property "Val" "100n"
			(at 78.105 207.01 90)
			(effects
				(font
					(size 1.27 1.27)
					(thickness 0.15)
				)
				(justify right)
			)
		)
		(property "License" "Apache-2.0"
			(at 99.06 223.52 0)
			(effects
				(font
					(size 1.27 1.27)
					(thickness 0.15)
				)
				(justify left bottom)
				(hide yes)
			)
		)
		(property "Author" "Antmicro"
			(at 101.6 223.52 0)
			(effects
				(font
					(size 1.27 1.27)
					(thickness 0.15)
				)
				(justify left bottom)
				(hide yes)
			)
		)
		(property "Voltage" "50V"
			(at 104.14 223.52 0)
			(effects
				(font
					(size 1.27 1.27)
				)
				(justify left bottom)
				(hide yes)
			)
		)
		(property "Dielectric" "X5R"
			(at 106.68 223.52 0)
			(effects
				(font
					(size 1.27 1.27)
				)
				(justify left bottom)
				(hide yes)
			)
		)
		(pin "1"
		)
		(pin "2"
		)
		(instances
			(project "jetson-orin-baseboard"
				(path ""
					(reference "C42")
					(unit 1)
				)
			)
		)
	)
	(symbol
		(lib_id "antmicroTestPoints:TP_0.75mm_SMD")
		(at 97.79 86.36 0)
		(unit 1)
		(exclude_from_sim no)
		(in_bom no)
		(on_board yes)
		(dnp no)
		(property "Reference" "TP38"
			(at 101.6 86.3599 0)
			(effects
				(font
					(size 1.27 1.27)
				)
				(justify left)
			)
		)
		(property "Value" "TP_0.75mm_SMD"
			(at 107.95 90.17 0)
			(effects
				(font
					(size 1.27 1.27)
					(thickness 0.15)
				)
				(justify left bottom)
				(hide yes)
			)
		)
		(property "Footprint" "antmicro-footprints:TP_SMD_0.75mm"
			(at 107.95 92.71 0)
			(effects
				(font
					(size 1.27 1.27)
					(thickness 0.15)
				)
				(justify left bottom)
				(hide yes)
			)
		)
		(property "Datasheet" ""
			(at 115.57 99.06 0)
			(effects
				(font
					(size 1.27 1.27)
					(thickness 0.15)
				)
				(justify left bottom)
				(hide yes)
			)
		)
		(property "Description" ""
			(at 97.79 86.36 0)
			(effects
				(font
					(size 1.27 1.27)
				)
				(hide yes)
			)
		)
		(property "MPN" ""
			(at 108.585 97.79 0)
			(effects
				(font
					(size 1.27 1.27)
					(thickness 0.15)
				)
				(justify left bottom)
				(hide yes)
			)
		)
		(property "Manufacturer" ""
			(at 108.585 92.71 0)
			(effects
				(font
					(size 1.27 1.27)
					(thickness 0.15)
				)
				(justify left bottom)
				(hide yes)
			)
		)
		(property "Author" "Antmicro"
			(at 107.95 95.25 0)
			(effects
				(font
					(size 1.27 1.27)
					(thickness 0.15)
				)
				(justify left bottom)
				(hide yes)
			)
		)
		(property "License" "Apache-2.0"
			(at 107.95 97.79 0)
			(effects
				(font
					(size 1.27 1.27)
					(thickness 0.15)
				)
				(justify left bottom)
				(hide yes)
			)
		)
		(pin "1"
		)
		(instances
			(project "jetson-orin-baseboard"
				(path ""
					(reference "TP38")
					(unit 1)
				)
			)
		)
	)
	(symbol
		(lib_id "antmicroResistors0402:R_4k7_0402")
		(at 232.41 219.71 90)
		(unit 1)
		(exclude_from_sim no)
		(in_bom yes)
		(on_board yes)
		(dnp no)
		(property "Reference" "R9"
			(at 233.68 215.9 90)
			(effects
				(font
					(size 1.27 1.27)
				)
				(justify right)
			)
		)
		(property "Value" "R_4k7_0402"
			(at 245.11 199.39 0)
			(effects
				(font
					(size 1.27 1.27)
					(thickness 0.15)
				)
				(justify left bottom)
				(hide yes)
			)
		)
		(property "Footprint" "antmicro-footprints:R_0402_1005Metric"
			(at 247.65 199.39 0)
			(effects
				(font
					(size 1.27 1.27)
					(thickness 0.15)
				)
				(justify left bottom)
				(hide yes)
			)
		)
		(property "Datasheet" "https://www.bourns.com/docs/product-datasheets/cr.pdf"
			(at 250.19 199.39 0)
			(effects
				(font
					(size 1.27 1.27)
					(thickness 0.15)
				)
				(justify left bottom)
				(hide yes)
			)
		)
		(property "Description" ""
			(at 232.41 219.71 0)
			(effects
				(font
					(size 1.27 1.27)
				)
				(hide yes)
			)
		)
		(property "Manufacturer" "Bourns"
			(at 255.27 199.39 0)
			(effects
				(font
					(size 1.27 1.27)
					(thickness 0.15)
				)
				(justify left bottom)
				(hide yes)
			)
		)
		(property "MPN" "CR0402-FX-4701GLF"
			(at 252.73 199.39 0)
			(effects
				(font
					(size 1.27 1.27)
					(thickness 0.15)
				)
				(justify left bottom)
				(hide yes)
			)
		)
		(property "Val" "4k7"
			(at 233.68 218.44 90)
			(effects
				(font
					(size 1.27 1.27)
					(thickness 0.15)
				)
				(justify right)
			)
		)
		(property "License" "Apache-2.0"
			(at 257.81 199.39 0)
			(effects
				(font
					(size 1.27 1.27)
					(thickness 0.15)
				)
				(justify left bottom)
				(hide yes)
			)
		)
		(property "Author" "Antmicro"
			(at 260.35 199.39 0)
			(effects
				(font
					(size 1.27 1.27)
					(thickness 0.15)
				)
				(justify left bottom)
				(hide yes)
			)
		)
		(property "Tolerance" "1%"
			(at 242.57 199.39 0)
			(effects
				(font
					(size 1.27 1.27)
				)
				(justify left bottom)
				(hide yes)
			)
		)
		(pin "1"
		)
		(pin "2"
		)
		(instances
			(project "jetson-orin-baseboard"
				(path ""
					(reference "R9")
					(unit 1)
				)
			)
		)
	)
	(symbol
		(lib_id "antmicroResistors0402:R_0R_0402")
		(at 35.56 99.06 90)
		(unit 1)
		(exclude_from_sim no)
		(in_bom yes)
		(on_board yes)
		(dnp no)
		(property "Reference" "R168"
			(at 36.83 95.25 90)
			(effects
				(font
					(size 1.27 1.27)
				)
				(justify right)
			)
		)
		(property "Value" "R_0R_0402"
			(at 48.26 78.74 0)
			(effects
				(font
					(size 1.27 1.27)
					(thickness 0.15)
				)
				(justify left bottom)
				(hide yes)
			)
		)
		(property "Footprint" "antmicro-footprints:R_0402_1005Metric"
			(at 50.8 78.74 0)
			(effects
				(font
					(size 1.27 1.27)
					(thickness 0.15)
				)
				(justify left bottom)
				(hide yes)
			)
		)
		(property "Datasheet" "https://industrial.panasonic.com/cdbs/www-data/pdf/RDA0000/AOA0000C301.pdf"
			(at 53.34 78.74 0)
			(effects
				(font
					(size 1.27 1.27)
					(thickness 0.15)
				)
				(justify left bottom)
				(hide yes)
			)
		)
		(property "Description" ""
			(at 35.56 99.06 0)
			(effects
				(font
					(size 1.27 1.27)
				)
				(hide yes)
			)
		)
		(property "Manufacturer" "Panasonic"
			(at 58.42 78.74 0)
			(effects
				(font
					(size 1.27 1.27)
					(thickness 0.15)
				)
				(justify left bottom)
				(hide yes)
			)
		)
		(property "MPN" "ERJ2GE0R00X"
			(at 55.88 78.74 0)
			(effects
				(font
					(size 1.27 1.27)
					(thickness 0.15)
				)
				(justify left bottom)
				(hide yes)
			)
		)
		(property "Val" "0R"
			(at 36.83 97.79 90)
			(effects
				(font
					(size 1.27 1.27)
					(thickness 0.15)
				)
				(justify right)
			)
		)
		(property "License" "Apache-2.0"
			(at 60.96 78.74 0)
			(effects
				(font
					(size 1.27 1.27)
					(thickness 0.15)
				)
				(justify left bottom)
				(hide yes)
			)
		)
		(property "Author" "Antmicro"
			(at 63.5 78.74 0)
			(effects
				(font
					(size 1.27 1.27)
					(thickness 0.15)
				)
				(justify left bottom)
				(hide yes)
			)
		)
		(property "Tolerance" "~"
			(at 45.72 78.74 0)
			(effects
				(font
					(size 1.27 1.27)
				)
				(justify left bottom)
				(hide yes)
			)
		)
		(property "Current" "1A"
			(at 66.04 78.74 0)
			(effects
				(font
					(size 1.27 1.27)
					(thickness 0.15)
				)
				(justify left bottom)
				(hide yes)
			)
		)
		(pin "1"
		)
		(pin "2"
		)
		(instances
			(project "jetson-orin-baseboard"
				(path ""
					(reference "R168")
					(unit 1)
				)
			)
		)
	)
	(symbol
		(lib_id "antmicropower:+3V3")
		(at 185.42 232.41 0)
		(unit 1)
		(exclude_from_sim no)
		(in_bom yes)
		(on_board yes)
		(dnp no)
		(property "Reference" "#PWR0170"
			(at 185.42 236.22 0)
			(effects
				(font
					(size 1.27 1.27)
				)
				(justify left bottom)
				(hide yes)
			)
		)
		(property "Value" "+3V3"
			(at 182.245 228.6 0)
			(effects
				(font
					(size 1.27 1.27)
					(thickness 0.15)
				)
				(justify left)
			)
		)
		(property "Footprint" ""
			(at 200.66 240.03 0)
			(effects
				(font
					(size 1.27 1.27)
					(thickness 0.15)
				)
				(justify left bottom)
				(hide yes)
			)
		)
		(property "Datasheet" ""
			(at 200.66 242.57 0)
			(effects
				(font
					(size 1.27 1.27)
					(thickness 0.15)
				)
				(justify left bottom)
				(hide yes)
			)
		)
		(property "Description" ""
			(at 185.42 232.41 0)
			(effects
				(font
					(size 1.27 1.27)
				)
				(hide yes)
			)
		)
		(property "Author" "Antmicro"
			(at 200.66 234.95 0)
			(effects
				(font
					(size 1.27 1.27)
					(thickness 0.15)
				)
				(justify left bottom)
				(hide yes)
			)
		)
		(property "License" "Apache-2.0"
			(at 200.66 237.49 0)
			(effects
				(font
					(size 1.27 1.27)
					(thickness 0.15)
				)
				(justify left bottom)
				(hide yes)
			)
		)
		(pin "1"
		)
		(instances
			(project "jetson-orin-baseboard"
				(path ""
					(reference "#PWR0170")
					(unit 1)
				)
			)
		)
	)
	(symbol
		(lib_id "antmicroLogicTranslatorsLevelShifters:NTS0102_XSON")
		(at 342.9 238.76 0)
		(unit 1)
		(exclude_from_sim no)
		(in_bom yes)
		(on_board yes)
		(dnp no)
		(fields_autoplaced yes)
		(property "Reference" "U32"
			(at 353.06 231.14 0)
			(effects
				(font
					(size 1.27 1.27)
				)
			)
		)
		(property "Value" "NTS0102_XSON"
			(at 378.46 246.38 0)
			(effects
				(font
					(size 1.27 1.27)
					(thickness 0.15)
				)
				(justify left bottom)
				(hide yes)
			)
		)
		(property "Footprint" "antmicro-footprints:XSON-8_1x1.95mm_P0.5mm"
			(at 378.46 248.92 0)
			(effects
				(font
					(size 1.27 1.27)
					(thickness 0.15)
				)
				(justify left bottom)
				(hide yes)
			)
		)
		(property "Datasheet" "http://www.farnell.com/datasheets/1760723.pdf"
			(at 378.46 251.46 0)
			(effects
				(font
					(size 1.27 1.27)
					(thickness 0.15)
				)
				(justify left bottom)
				(hide yes)
			)
		)
		(property "Description" ""
			(at 342.9 238.76 0)
			(effects
				(font
					(size 1.27 1.27)
				)
				(hide yes)
			)
		)
		(property "MPN" "NTS0102GT"
			(at 353.06 233.68 0)
			(effects
				(font
					(size 1.27 1.27)
					(thickness 0.15)
				)
			)
		)
		(property "Manufacturer" "NXP"
			(at 378.46 254 0)
			(effects
				(font
					(size 1.27 1.27)
					(thickness 0.15)
				)
				(justify left bottom)
				(hide yes)
			)
		)
		(property "Author" "Antmicro"
			(at 378.46 256.54 0)
			(effects
				(font
					(size 1.27 1.27)
					(thickness 0.15)
				)
				(justify left bottom)
				(hide yes)
			)
		)
		(property "License" "Apache-2.0"
			(at 378.46 259.08 0)
			(effects
				(font
					(size 1.27 1.27)
					(thickness 0.15)
				)
				(justify left bottom)
				(hide yes)
			)
		)
		(pin "1"
		)
		(pin "2"
		)
		(pin "3"
		)
		(pin "4"
		)
		(pin "5"
		)
		(pin "6"
		)
		(pin "7"
		)
		(pin "8"
		)
		(instances
			(project "jetson-orin-baseboard"
				(path ""
					(reference "U32")
					(unit 1)
				)
			)
		)
	)
	(symbol
		(lib_id "antmicropower:GND")
		(at 175.26 256.54 0)
		(unit 1)
		(exclude_from_sim no)
		(in_bom yes)
		(on_board yes)
		(dnp no)
		(property "Reference" "#PWR0216"
			(at 175.26 262.89 0)
			(effects
				(font
					(size 1.27 1.27)
				)
				(justify left bottom)
				(hide yes)
			)
		)
		(property "Value" "GND"
			(at 175.26 260.35 0)
			(effects
				(font
					(size 1.27 1.27)
					(thickness 0.15)
				)
			)
		)
		(property "Footprint" ""
			(at 184.15 264.16 0)
			(effects
				(font
					(size 1.27 1.27)
					(thickness 0.15)
				)
				(justify left bottom)
				(hide yes)
			)
		)
		(property "Datasheet" ""
			(at 184.15 269.24 0)
			(effects
				(font
					(size 1.27 1.27)
					(thickness 0.15)
				)
				(justify left bottom)
				(hide yes)
			)
		)
		(property "Description" ""
			(at 175.26 256.54 0)
			(effects
				(font
					(size 1.27 1.27)
				)
				(hide yes)
			)
		)
		(property "Author" "Antmicro"
			(at 184.15 264.16 0)
			(effects
				(font
					(size 1.27 1.27)
					(thickness 0.15)
				)
				(justify left bottom)
				(hide yes)
			)
		)
		(property "License" "Apache-2.0"
			(at 184.15 266.7 0)
			(effects
				(font
					(size 1.27 1.27)
					(thickness 0.15)
				)
				(justify left bottom)
				(hide yes)
			)
		)
		(pin "1"
		)
		(instances
			(project "jetson-orin-baseboard"
				(path ""
					(reference "#PWR0216")
					(unit 1)
				)
			)
		)
	)
	(symbol
		(lib_id "antmicropower:GND")
		(at 218.44 254 0)
		(unit 1)
		(exclude_from_sim no)
		(in_bom yes)
		(on_board yes)
		(dnp no)
		(property "Reference" "#PWR0362"
			(at 218.44 260.35 0)
			(effects
				(font
					(size 1.27 1.27)
				)
				(justify left bottom)
				(hide yes)
			)
		)
		(property "Value" "GND"
			(at 218.44 257.81 0)
			(effects
				(font
					(size 1.27 1.27)
					(thickness 0.15)
				)
			)
		)
		(property "Footprint" ""
			(at 227.33 261.62 0)
			(effects
				(font
					(size 1.27 1.27)
					(thickness 0.15)
				)
				(justify left bottom)
				(hide yes)
			)
		)
		(property "Datasheet" ""
			(at 227.33 266.7 0)
			(effects
				(font
					(size 1.27 1.27)
					(thickness 0.15)
				)
				(justify left bottom)
				(hide yes)
			)
		)
		(property "Description" ""
			(at 218.44 254 0)
			(effects
				(font
					(size 1.27 1.27)
				)
				(hide yes)
			)
		)
		(property "Author" "Antmicro"
			(at 227.33 261.62 0)
			(effects
				(font
					(size 1.27 1.27)
					(thickness 0.15)
				)
				(justify left bottom)
				(hide yes)
			)
		)
		(property "License" "Apache-2.0"
			(at 227.33 264.16 0)
			(effects
				(font
					(size 1.27 1.27)
					(thickness 0.15)
				)
				(justify left bottom)
				(hide yes)
			)
		)
		(pin "1"
		)
		(instances
			(project "jetson-orin-baseboard"
				(path ""
					(reference "#PWR0362")
					(unit 1)
				)
			)
		)
	)
	(symbol
		(lib_id "antmicroResistorNetworksArrays:R_4x2k2_0201_array")
		(at 78.74 151.13 90)
		(unit 1)
		(exclude_from_sim no)
		(in_bom yes)
		(on_board yes)
		(dnp no)
		(fields_autoplaced yes)
		(property "Reference" "R48"
			(at 88.9 144.78 90)
			(effects
				(font
					(size 1.27 1.27)
				)
				(justify right)
			)
		)
		(property "Value" "R_4x2k2_0201_array"
			(at 86.36 124.46 0)
			(effects
				(font
					(size 1.27 1.27)
					(thickness 0.15)
				)
				(justify left bottom)
				(hide yes)
			)
		)
		(property "Footprint" "antmicro-footprints:R_Array_4x0201_Panasonic_EXB18V"
			(at 91.44 124.46 0)
			(effects
				(font
					(size 1.27 1.27)
					(thickness 0.15)
				)
				(justify left bottom)
				(hide yes)
			)
		)
		(property "Datasheet" "http://industrial.panasonic.com/cdbs/www-data/pdf/AOC0000/AOC0000C14.pdf"
			(at 93.98 124.46 0)
			(effects
				(font
					(size 1.27 1.27)
					(thickness 0.15)
				)
				(justify left bottom)
				(hide yes)
			)
		)
		(property "Description" ""
			(at 78.74 151.13 0)
			(effects
				(font
					(size 1.27 1.27)
				)
				(hide yes)
			)
		)
		(property "MPN" "EXB-18V222JX"
			(at 96.52 124.46 0)
			(effects
				(font
					(size 1.27 1.27)
					(thickness 0.15)
				)
				(justify left bottom)
				(hide yes)
			)
		)
		(property "Manufacturer" "Panasonic"
			(at 99.06 124.46 0)
			(effects
				(font
					(size 1.27 1.27)
					(thickness 0.15)
				)
				(justify left bottom)
				(hide yes)
			)
		)
		(property "Val" "4x2k2_0201"
			(at 88.9 147.32 90)
			(effects
				(font
					(size 1.27 1.27)
					(thickness 0.15)
				)
				(justify right)
			)
		)
		(property "Author" "Antmicro"
			(at 101.6 124.46 0)
			(effects
				(font
					(size 1.27 1.27)
					(thickness 0.15)
				)
				(justify left bottom)
				(hide yes)
			)
		)
		(property "License" "Apache-2.0"
			(at 104.14 124.46 0)
			(effects
				(font
					(size 1.27 1.27)
					(thickness 0.15)
				)
				(justify left bottom)
				(hide yes)
			)
		)
		(pin "1"
		)
		(pin "2"
		)
		(pin "3"
		)
		(pin "4"
		)
		(pin "5"
		)
		(pin "6"
		)
		(pin "7"
		)
		(pin "8"
		)
		(instances
			(project "jetson-orin-baseboard"
				(path ""
					(reference "R48")
					(unit 1)
				)
			)
		)
	)
	(symbol
		(lib_id "antmicropower:GND")
		(at 60.96 105.41 0)
		(unit 1)
		(exclude_from_sim no)
		(in_bom yes)
		(on_board yes)
		(dnp no)
		(property "Reference" "#PWR0160"
			(at 60.96 111.76 0)
			(effects
				(font
					(size 1.27 1.27)
				)
				(justify left bottom)
				(hide yes)
			)
		)
		(property "Value" "GND"
			(at 60.96 109.22 0)
			(effects
				(font
					(size 1.27 1.27)
					(thickness 0.15)
				)
			)
		)
		(property "Footprint" ""
			(at 69.85 113.03 0)
			(effects
				(font
					(size 1.27 1.27)
					(thickness 0.15)
				)
				(justify left bottom)
				(hide yes)
			)
		)
		(property "Datasheet" ""
			(at 69.85 118.11 0)
			(effects
				(font
					(size 1.27 1.27)
					(thickness 0.15)
				)
				(justify left bottom)
				(hide yes)
			)
		)
		(property "Description" ""
			(at 60.96 105.41 0)
			(effects
				(font
					(size 1.27 1.27)
				)
				(hide yes)
			)
		)
		(property "Author" "Antmicro"
			(at 69.85 113.03 0)
			(effects
				(font
					(size 1.27 1.27)
					(thickness 0.15)
				)
				(justify left bottom)
				(hide yes)
			)
		)
		(property "License" "Apache-2.0"
			(at 69.85 115.57 0)
			(effects
				(font
					(size 1.27 1.27)
					(thickness 0.15)
				)
				(justify left bottom)
				(hide yes)
			)
		)
		(pin "1"
		)
		(instances
			(project "jetson-orin-baseboard"
				(path ""
					(reference "#PWR0160")
					(unit 1)
				)
			)
		)
	)
	(symbol
		(lib_id "antmicropower:+3V3")
		(at 64.77 129.54 0)
		(unit 1)
		(exclude_from_sim no)
		(in_bom yes)
		(on_board yes)
		(dnp no)
		(property "Reference" "#PWR0330"
			(at 64.77 133.35 0)
			(effects
				(font
					(size 1.27 1.27)
				)
				(justify left bottom)
				(hide yes)
			)
		)
		(property "Value" "+3V3"
			(at 64.135 125.73 0)
			(effects
				(font
					(size 1.27 1.27)
					(thickness 0.15)
				)
			)
		)
		(property "Footprint" ""
			(at 80.01 137.16 0)
			(effects
				(font
					(size 1.27 1.27)
					(thickness 0.15)
				)
				(justify left bottom)
				(hide yes)
			)
		)
		(property "Datasheet" ""
			(at 80.01 139.7 0)
			(effects
				(font
					(size 1.27 1.27)
					(thickness 0.15)
				)
				(justify left bottom)
				(hide yes)
			)
		)
		(property "Description" ""
			(at 64.77 129.54 0)
			(effects
				(font
					(size 1.27 1.27)
				)
				(hide yes)
			)
		)
		(property "Author" "Antmicro"
			(at 80.01 132.08 0)
			(effects
				(font
					(size 1.27 1.27)
					(thickness 0.15)
				)
				(justify left bottom)
				(hide yes)
			)
		)
		(property "License" "Apache-2.0"
			(at 80.01 134.62 0)
			(effects
				(font
					(size 1.27 1.27)
					(thickness 0.15)
				)
				(justify left bottom)
				(hide yes)
			)
		)
		(pin "1"
		)
		(instances
			(project "jetson-orin-baseboard"
				(path ""
					(reference "#PWR0330")
					(unit 1)
				)
			)
		)
	)
	(symbol
		(lib_id "antmicroResistorNetworksArrays:R_4x0R_0201_array")
		(at 157.48 67.31 0)
		(mirror x)
		(unit 1)
		(exclude_from_sim no)
		(in_bom no)
		(on_board yes)
		(dnp yes)
		(property "Reference" "R103"
			(at 162.56 53.975 0)
			(effects
				(font
					(size 1.27 1.27)
				)
			)
		)
		(property "Value" "R_4x0R_0201_array"
			(at 184.15 59.69 0)
			(effects
				(font
					(size 1.27 1.27)
					(thickness 0.15)
				)
				(justify left bottom)
				(hide yes)
			)
		)
		(property "Footprint" "antmicro-footprints:R_Array_4x0201_Panasonic_EXB18V"
			(at 184.15 54.61 0)
			(effects
				(font
					(size 1.27 1.27)
					(thickness 0.15)
				)
				(justify left bottom)
				(hide yes)
			)
		)
		(property "Datasheet" "http://industrial.panasonic.com/cdbs/www-data/pdf/AOC0000/AOC0000C14.pdf"
			(at 184.15 52.07 0)
			(effects
				(font
					(size 1.27 1.27)
					(thickness 0.15)
				)
				(justify left bottom)
				(hide yes)
			)
		)
		(property "Description" ""
			(at 157.48 67.31 0)
			(effects
				(font
					(size 1.27 1.27)
				)
				(hide yes)
			)
		)
		(property "MPN" "EXB-18VR000X"
			(at 184.15 49.53 0)
			(effects
				(font
					(size 1.27 1.27)
					(thickness 0.15)
				)
				(justify left bottom)
				(hide yes)
			)
		)
		(property "Manufacturer" "Panasonic"
			(at 184.15 46.99 0)
			(effects
				(font
					(size 1.27 1.27)
					(thickness 0.15)
				)
				(justify left bottom)
				(hide yes)
			)
		)
		(property "Val" "4x0R_0201"
			(at 162.56 56.515 0)
			(effects
				(font
					(size 1.27 1.27)
					(thickness 0.15)
				)
			)
		)
		(property "Author" "Antmicro"
			(at 184.15 44.45 0)
			(effects
				(font
					(size 1.27 1.27)
					(thickness 0.15)
				)
				(justify left bottom)
				(hide yes)
			)
		)
		(property "License" "Apache-2.0"
			(at 184.15 41.91 0)
			(effects
				(font
					(size 1.27 1.27)
					(thickness 0.15)
				)
				(justify left bottom)
				(hide yes)
			)
		)
		(pin "1"
		)
		(pin "2"
		)
		(pin "3"
		)
		(pin "4"
		)
		(pin "5"
		)
		(pin "6"
		)
		(pin "7"
		)
		(pin "8"
		)
		(instances
			(project "jetson-orin-baseboard"
				(path ""
					(reference "R103")
					(unit 1)
				)
			)
		)
	)
	(symbol
		(lib_id "antmicropower:+3V3")
		(at 372.11 195.58 0)
		(unit 1)
		(exclude_from_sim no)
		(in_bom yes)
		(on_board yes)
		(dnp no)
		(property "Reference" "#PWR0209"
			(at 372.11 199.39 0)
			(effects
				(font
					(size 1.27 1.27)
				)
				(justify left bottom)
				(hide yes)
			)
		)
		(property "Value" "+3V3"
			(at 368.935 191.77 0)
			(effects
				(font
					(size 1.27 1.27)
					(thickness 0.15)
				)
				(justify left)
			)
		)
		(property "Footprint" ""
			(at 387.35 203.2 0)
			(effects
				(font
					(size 1.27 1.27)
					(thickness 0.15)
				)
				(justify left bottom)
				(hide yes)
			)
		)
		(property "Datasheet" ""
			(at 387.35 205.74 0)
			(effects
				(font
					(size 1.27 1.27)
					(thickness 0.15)
				)
				(justify left bottom)
				(hide yes)
			)
		)
		(property "Description" ""
			(at 372.11 195.58 0)
			(effects
				(font
					(size 1.27 1.27)
				)
				(hide yes)
			)
		)
		(property "Author" "Antmicro"
			(at 387.35 198.12 0)
			(effects
				(font
					(size 1.27 1.27)
					(thickness 0.15)
				)
				(justify left bottom)
				(hide yes)
			)
		)
		(property "License" "Apache-2.0"
			(at 387.35 200.66 0)
			(effects
				(font
					(size 1.27 1.27)
					(thickness 0.15)
				)
				(justify left bottom)
				(hide yes)
			)
		)
		(pin "1"
		)
		(instances
			(project "jetson-orin-baseboard"
				(path ""
					(reference "#PWR0209")
					(unit 1)
				)
			)
		)
	)
	(symbol
		(lib_id "antmicroResistorNetworksArrays:R_4x0R_0201_array")
		(at 350.52 129.54 0)
		(unit 1)
		(exclude_from_sim no)
		(in_bom yes)
		(on_board yes)
		(dnp no)
		(property "Reference" "R51"
			(at 355.6 123.825 0)
			(effects
				(font
					(size 1.27 1.27)
				)
			)
		)
		(property "Value" "R_4x0R_0201_array"
			(at 377.19 137.16 0)
			(effects
				(font
					(size 1.27 1.27)
					(thickness 0.15)
				)
				(justify left bottom)
				(hide yes)
			)
		)
		(property "Footprint" "antmicro-footprints:R_Array_4x0201_Panasonic_EXB18V"
			(at 377.19 142.24 0)
			(effects
				(font
					(size 1.27 1.27)
					(thickness 0.15)
				)
				(justify left bottom)
				(hide yes)
			)
		)
		(property "Datasheet" "http://industrial.panasonic.com/cdbs/www-data/pdf/AOC0000/AOC0000C14.pdf"
			(at 377.19 144.78 0)
			(effects
				(font
					(size 1.27 1.27)
					(thickness 0.15)
				)
				(justify left bottom)
				(hide yes)
			)
		)
		(property "Description" ""
			(at 350.52 129.54 0)
			(effects
				(font
					(size 1.27 1.27)
				)
				(hide yes)
			)
		)
		(property "MPN" "EXB-18VR000X"
			(at 377.19 147.32 0)
			(effects
				(font
					(size 1.27 1.27)
					(thickness 0.15)
				)
				(justify left bottom)
				(hide yes)
			)
		)
		(property "Manufacturer" "Panasonic"
			(at 377.19 149.86 0)
			(effects
				(font
					(size 1.27 1.27)
					(thickness 0.15)
				)
				(justify left bottom)
				(hide yes)
			)
		)
		(property "Val" "4x0R_0201"
			(at 355.6 126.365 0)
			(effects
				(font
					(size 1.27 1.27)
					(thickness 0.15)
				)
			)
		)
		(property "Author" "Antmicro"
			(at 377.19 152.4 0)
			(effects
				(font
					(size 1.27 1.27)
					(thickness 0.15)
				)
				(justify left bottom)
				(hide yes)
			)
		)
		(property "License" "Apache-2.0"
			(at 377.19 154.94 0)
			(effects
				(font
					(size 1.27 1.27)
					(thickness 0.15)
				)
				(justify left bottom)
				(hide yes)
			)
		)
		(pin "1"
		)
		(pin "2"
		)
		(pin "3"
		)
		(pin "4"
		)
		(pin "5"
		)
		(pin "6"
		)
		(pin "7"
		)
		(pin "8"
		)
		(instances
			(project "jetson-orin-baseboard"
				(path ""
					(reference "R51")
					(unit 1)
				)
			)
		)
	)
)
